FILE_TYPE = MACRO_DRAWING;
SET COLOR_WIRE YELLOW;
SET COLOR_PROP ORANGE;
SET COLOR_DOT WHITE;
SET COLOR_ARC YELLOW;
SET COLOR_BODY GREEN;
SET COLOR_NOTE PURPLE;
SET PROP_DISPLAY VALUE;
SET PAGE_NUMBER P232;
FORCEADD OFFPAGE..1
(-3050 -2375);
FORCEPROP 2 LAST $XR0 244 
J 0
(-3332 -2375);
DISPLAY 0.638298 (-3332 -2375);
PAINT MONO (-3332 -2375);
FORCEPROP 1 LAST COMMENT_BODY TRUE
J 0
(-2925 -2475);
DISPLAY 0.872340 (-2925 -2475);
PAINT GREEN (-2925 -2475);
DISPLAY INVISIBLE (-2925 -2475);
FORCEPROP 1 LAST OFFPAGE TRUE
J 0
(-2725 -2500);
DISPLAY 0.872340 (-2725 -2500);
DISPLAY INVISIBLE (-2725 -2500);
FORCEPROP 2 LAST CDS_LIB standard
J 0
(-3050 -2375);
DISPLAY INVISIBLE (-3050 -2375);
FORCEPROP 2 LAST BOM_COST VR_SYSTEM 
J 0
(-3300 -2325);
DISPLAY 0.829787 (-3300 -2325);
PAINT PURPLE (-3300 -2325);
DISPLAY INVISIBLE (-3300 -2325);
FORCEPROP 2 LAST PATH I1
J 0
(-3325 -2325);
DISPLAY 1.021277 (-3325 -2325);
DISPLAY INVISIBLE (-3325 -2325);
FORCEADD UNIVERSAL_GND..1
(-1175 -2725);
FORCEPROP 3 LASTPIN (-1175 -2675) SIG_NAME GND\g
J 0
(-1165 -2665);
DISPLAY 0.659574 (-1165 -2665);
PAINT MONO (-1165 -2665);
DISPLAY INVISIBLE (-1165 -2665);
FORCEPROP 1 LAST HDL_POWER GND
J 1
(-1150 -2800);
DISPLAY 0.872340 (-1150 -2800);
PAINT GREEN (-1150 -2800);
DISPLAY INVISIBLE (-1150 -2800);
FORCEPROP 2 LAST CDS_LIB logical_power
J 0
(-1175 -2725);
PAINT MONO (-1175 -2725);
DISPLAY INVISIBLE (-1175 -2725);
FORCEPROP 1 LAST PATH I10
J 0
(-1100 -2725);
DISPLAY 0.872340 (-1100 -2725);
PAINT AQUA (-1100 -2725);
DISPLAY INVISIBLE (-1100 -2725);
FORCEADD 74LVC1G07SE7..1
(-800 -2300);
FORCEPROP 1 LAST PART_NUMBER AL1G07SE000
J 0
(-944 -2016);
DISPLAY 0.723404 (-944 -2016);
PAINT GREEN (-944 -2016);
DISPLAY INVISIBLE (-944 -2016);
FORCEPROP 1 LAST MATERIAL IC
J 0
(-944 -2143);
DISPLAY 0.723404 (-944 -2143);
PAINT GREEN (-944 -2143);
FORCEPROP 2 LAST VALUE 74LVC1G07SE-7
J 0
(-1000 -1925);
DISPLAY 0.638298 (-1000 -1925);
FORCEPROP 2 LAST PART_TYPE SMLF
J 0
(-1000 -1875);
DISPLAY 0.638298 (-1000 -1875);
FORCEPROP 1 LAST $LOCATION U95
J 0
(-1000 -1850);
DISPLAY 0.723404 (-1000 -1850);
PAINT GREEN (-1000 -1850);
FORCEPROP 2 LASTPIN (-1100 -2300) $PN 2
J 2
(-1110 -2290);
DISPLAY 0.680851 (-1110 -2290);
PAINT MONO (-1110 -2290);
FORCEPROP 2 LASTPIN (-1100 -2400) $PN 3
J 2
(-1110 -2390);
DISPLAY 0.680851 (-1110 -2390);
PAINT MONO (-1110 -2390);
FORCEPROP 2 LASTPIN (-500 -2400) $PN 1
J 0
(-490 -2390);
DISPLAY 0.680851 (-490 -2390);
PAINT MONO (-490 -2390);
FORCEPROP 2 LASTPIN (-1100 -2200) $PN 5
J 2
(-1110 -2190);
DISPLAY 0.680851 (-1110 -2190);
PAINT MONO (-1110 -2190);
FORCEPROP 2 LASTPIN (-500 -2300) $PN 4
J 0
(-490 -2290);
DISPLAY 0.680851 (-490 -2290);
PAINT MONO (-490 -2290);
FORCEPROP 2 LAST SEC_TYPE 
J 0
(-925 -1825);
DISPLAY 1.021277 (-925 -1825);
DISPLAY INVISIBLE (-925 -1825);
FORCEPROP 2 LAST CDS_LIB pure_quanta
J 0
(-800 -2300);
DISPLAY INVISIBLE (-800 -2300);
FORCEPROP 1 LAST CDS_LMAN_SYM_OUTLINE -150,150,150,-150
J 0
(-800 -2300);
DISPLAY 0.468085 (-800 -2300);
PAINT GREEN (-800 -2300);
DISPLAY INVISIBLE (-800 -2300);
FORCEPROP 1 LAST NEEDS_NO_SIZE TRUE
J 0
(-800 -2300);
DISPLAY 0.723404 (-800 -2300);
PAINT GREEN (-800 -2300);
DISPLAY INVISIBLE (-800 -2300);
FORCEPROP 1 LAST PATH I11
J 0
(-800 -2300);
DISPLAY 0.723404 (-800 -2300);
PAINT GREEN (-800 -2300);
DISPLAY INVISIBLE (-800 -2300);
FORCEPROP 2 LAST CDS_LOCATION U95
J 0
(-1000 -1825);
DISPLAY 1.021277 (-1000 -1825);
DISPLAY INVISIBLE (-1000 -1825);
FORCEPROP 2 LAST SEC 1
J 0
(-925 -1825);
DISPLAY 0.680851 (-925 -1825);
PAINT MONO (-925 -1825);
DISPLAY INVISIBLE (-925 -1825);
FORCEADD UNIVERSAL_POWER..1
(-1175 -1750);
FORCEPROP 3 LASTPIN (-1175 -1800) SIG_NAME P3V3_AUX\g
J 0
(-1165 -1790);
DISPLAY 0.659574 (-1165 -1790);
PAINT MONO (-1165 -1790);
DISPLAY INVISIBLE (-1165 -1790);
FORCEPROP 1 LAST HDL_POWER P3V3_AUX
J 1
(-1175 -1700);
DISPLAY 0.872340 (-1175 -1700);
PAINT GREEN (-1175 -1700);
FORCEPROP 2 LAST CDS_LIB logical_power
J 0
(-1175 -1750);
PAINT MONO (-1175 -1750);
DISPLAY INVISIBLE (-1175 -1750);
FORCEPROP 1 LAST PATH I12
J 0
(-1125 -1725);
DISPLAY 0.872340 (-1125 -1725);
PAINT AQUA (-1125 -1725);
DISPLAY INVISIBLE (-1125 -1725);
FORCEADD Q_RES..1
(-875 -1500);
FORCEPROP 1 LAST PART_NUMBER CS00002JB13
J 0
(-975 -1450);
DISPLAY 0.404255 (-975 -1450);
DISPLAY INVISIBLE (-975 -1450);
FORCEPROP 1 LAST PACK_TYPE 0402LF
J 0
(-975 -1425);
DISPLAY 0.404255 (-975 -1425);
FORCEPROP 1 LAST WATTAGE 1/16W
J 2
(-750 -1425);
DISPLAY 0.404255 (-750 -1425);
FORCEPROP 1 LAST MATERIAL EMPTY
J 0
(-650 -1500);
DISPLAY 0.404255 (-650 -1500);
FORCEPROP 1 LAST TOLERANCE 5%
J 0
(-725 -1500);
DISPLAY 0.404255 (-725 -1500);
FORCEPROP 1 LAST VALUE 0
J 2
(-750 -1500);
DISPLAY 0.404255 (-750 -1500);
FORCEPROP 1 LAST $LOCATION R4807
J 0
(-1100 -1500);
DISPLAY 0.638298 (-1100 -1500);
FORCEPROP 1 LASTPIN (-975 -1500) $PN 1
J 0
(-963 -1488);
DISPLAY 0.787234 (-963 -1488);
PAINT MONO (-963 -1488);
FORCEPROP 1 LASTPIN (-775 -1500) $PN 2
J 0
(-813 -1488);
DISPLAY 0.787234 (-813 -1488);
PAINT MONO (-813 -1488);
FORCEPROP 2 LAST CDS_LIB pure_quanta
J 0
(-875 -1500);
DISPLAY INVISIBLE (-875 -1500);
FORCEPROP 1 LAST PATH I13
J 0
(-925 -1350);
DISPLAY 0.978723 (-925 -1350);
PAINT WHITE (-925 -1350);
DISPLAY INVISIBLE (-925 -1350);
FORCEPROP 0 LAST CDS_LOCATION R4807
J 0
(-750 -1400);
DISPLAY 1.021277 (-750 -1400);
DISPLAY INVISIBLE (-750 -1400);
FORCEPROP 0 LAST $SEC 1
J 0
(-750 -1400);
DISPLAY 0.680851 (-750 -1400);
PAINT MONO (-750 -1400);
DISPLAY INVISIBLE (-750 -1400);
FORCEPROP 0 LAST CDS_SEC 1
J 0
(-750 -1400);
DISPLAY 1.021277 (-750 -1400);
DISPLAY INVISIBLE (-750 -1400);
FORCEADD MOSFET_NCH_GDS_ESD_PROTECTED..1
R 2
(-150 -225);
FORCEPROP 1 LAST PART_NUMBER BAM70020002
J 2
(-292 -313);
DISPLAY 0.723404 (-292 -313);
PAINT GREEN (-292 -313);
DISPLAY INVISIBLE (-292 -313);
FORCEPROP 1 LAST MATERIAL IC
J 2
(-292 -370);
DISPLAY 0.723404 (-292 -370);
PAINT GREEN (-292 -370);
FORCEPROP 2 LAST VALUE 2N7002K
J 2
(-300 -175);
DISPLAY 0.680851 (-300 -175);
FORCEPROP 2 LAST PART_TYPE SMLF
J 2
(-300 -125);
DISPLAY 0.680851 (-300 -125);
FORCEPROP 1 LAST LOCATION Q52
J 2
(-292 -261);
DISPLAY 0.723404 (-292 -261);
PAINT GREEN (-292 -261);
FORCEPROP 0 LASTPIN (-175 -25) $PN D
R 1
J 0
(-185 -15);
DISPLAY 0.680851 (-185 -15);
PAINT MONO (-185 -15);
FORCEPROP 0 LASTPIN (25 -225) $PN G
J 0
(35 -215);
DISPLAY 0.680851 (35 -215);
PAINT MONO (35 -215);
FORCEPROP 0 LASTPIN (-175 -425) $PN S
R 1
J 2
(-185 -435);
DISPLAY 0.680851 (-185 -435);
PAINT MONO (-185 -435);
FORCEPROP 1 LAST NEEDS_NO_SIZE TRUE
J 2
(-275 -335);
DISPLAY 0.723404 (-275 -335);
PAINT GREEN (-275 -335);
DISPLAY INVISIBLE (-275 -335);
FORCEPROP 1 LAST CDS_LMAN_SYM_OUTLINE -125,150,125,-150
J 2
(-150 -225);
DISPLAY 0.468085 (-150 -225);
PAINT GREEN (-150 -225);
DISPLAY INVISIBLE (-150 -225);
FORCEPROP 2 LAST CDS_LIB pure_quanta
J 2
(-150 -225);
DISPLAY INVISIBLE (-150 -225);
FORCEPROP 1 LAST PATH I14
J 2
(-275 -375);
DISPLAY 0.723404 (-275 -375);
PAINT GREEN (-275 -375);
DISPLAY INVISIBLE (-275 -375);
FORCEPROP 0 LAST $SEC 1
J 0
(-300 -75);
DISPLAY 0.680851 (-300 -75);
PAINT MONO (-300 -75);
DISPLAY INVISIBLE (-300 -75);
FORCEPROP 0 LAST CDS_SEC 1
J 0
(-300 -75);
DISPLAY 1.021277 (-300 -75);
DISPLAY INVISIBLE (-300 -75);
FORCEADD UNIVERSAL_GND..1
(-175 -625);
FORCEPROP 3 LASTPIN (-175 -575) SIG_NAME GND\g
J 0
(-165 -565);
DISPLAY 0.659574 (-165 -565);
PAINT MONO (-165 -565);
DISPLAY INVISIBLE (-165 -565);
FORCEPROP 2 LAST CDS_LIB logical_power
J 0
(-175 -625);
PAINT MONO (-175 -625);
DISPLAY INVISIBLE (-175 -625);
FORCEPROP 1 LAST HDL_POWER GND
J 1
(-150 -700);
DISPLAY 0.872340 (-150 -700);
PAINT GREEN (-150 -700);
DISPLAY INVISIBLE (-150 -700);
FORCEPROP 1 LAST PATH I15
J 0
(-100 -625);
DISPLAY 0.872340 (-100 -625);
PAINT AQUA (-100 -625);
DISPLAY INVISIBLE (-100 -625);
FORCEADD Q_RES..2
R 2
(-2250 1650);
FORCEPROP 1 LAST PART_NUMBER CS26192FB03
J 2
(-2290 1525);
DISPLAY 0.404255 (-2290 1525);
DISPLAY INVISIBLE (-2290 1525);
FORCEPROP 1 LAST MATERIAL CHIP
J 2
(-2290 1575);
DISPLAY 0.510638 (-2290 1575);
FORCEPROP 1 LAST WATTAGE 1/16W
J 2
(-2290 1625);
DISPLAY 0.510638 (-2290 1625);
FORCEPROP 1 LAST PACK_TYPE 0402LF
J 2
(-2290 1475);
DISPLAY 0.510638 (-2290 1475);
FORCEPROP 1 LAST TOLERANCE 1%
J 2
(-2295 1675);
DISPLAY 0.510638 (-2295 1675);
FORCEPROP 1 LAST VALUE 6.19K
J 2
(-2295 1725);
DISPLAY 0.510638 (-2295 1725);
FORCEPROP 1 LAST $LOCATION R1689
J 2
(-2295 1775);
DISPLAY 0.510638 (-2295 1775);
FORCEPROP 1 LASTPIN (-2250 1750) $PN 1
J 2
(-2255 1712);
DISPLAY 0.787234 (-2255 1712);
FORCEPROP 1 LASTPIN (-2250 1550) $PN 2
J 2
(-2255 1560);
DISPLAY 0.787234 (-2255 1560);
FORCEPROP 2 LAST CDS_LIB pure_quanta
J 2
(-2250 1650);
PAINT MONO (-2250 1650);
DISPLAY INVISIBLE (-2250 1650);
FORCEPROP 1 LAST PATH I16
J 2
(-2300 1825);
DISPLAY 0.978723 (-2300 1825);
PAINT WHITE (-2300 1825);
DISPLAY INVISIBLE (-2300 1825);
FORCEPROP 2 LAST CDS_LOCATION R1689
J 2
(-2300 1875);
DISPLAY 1.021277 (-2300 1875);
DISPLAY INVISIBLE (-2300 1875);
FORCEPROP 2 LAST $SEC 1
J 2
(-2300 1875);
DISPLAY 0.680851 (-2300 1875);
PAINT MONO (-2300 1875);
DISPLAY INVISIBLE (-2300 1875);
FORCEPROP 2 LAST CDS_SEC 1
J 2
(-2300 1875);
DISPLAY 1.021277 (-2300 1875);
DISPLAY INVISIBLE (-2300 1875);
FORCEADD UNIVERSAL_GND..1
(-2250 1425);
FORCEPROP 3 LASTPIN (-2250 1475) SIG_NAME GND\g
J 0
(-2240 1485);
DISPLAY 0.659574 (-2240 1485);
PAINT MONO (-2240 1485);
DISPLAY INVISIBLE (-2240 1485);
FORCEPROP 2 LAST CDS_LIB logical_power
J 0
(-2250 1425);
PAINT MONO (-2250 1425);
DISPLAY INVISIBLE (-2250 1425);
FORCEPROP 1 LAST HDL_POWER GND
J 1
(-2225 1350);
DISPLAY 0.872340 (-2225 1350);
PAINT GREEN (-2225 1350);
DISPLAY INVISIBLE (-2225 1350);
FORCEPROP 1 LAST PATH I17
J 0
(-2175 1425);
DISPLAY 0.872340 (-2175 1425);
PAINT AQUA (-2175 1425);
DISPLAY INVISIBLE (-2175 1425);
FORCEADD Q_RES..2
R 2
(-2250 2075);
FORCEPROP 1 LAST PART_NUMBER CS41002FB09
J 2
(-2290 1950);
DISPLAY 0.404255 (-2290 1950);
DISPLAY INVISIBLE (-2290 1950);
FORCEPROP 1 LAST MATERIAL CHIP
J 2
(-2290 2000);
DISPLAY 0.510638 (-2290 2000);
FORCEPROP 1 LAST VALUE 100K
J 2
(-2295 2150);
DISPLAY 0.510638 (-2295 2150);
FORCEPROP 1 LAST PACK_TYPE 0402LF
J 2
(-2290 1900);
DISPLAY 0.510638 (-2290 1900);
FORCEPROP 1 LAST WATTAGE 1/16W
J 2
(-2290 2050);
DISPLAY 0.510638 (-2290 2050);
FORCEPROP 1 LAST TOLERANCE 1%
J 2
(-2295 2100);
DISPLAY 0.510638 (-2295 2100);
FORCEPROP 1 LAST $LOCATION R1688
J 2
(-2295 2200);
DISPLAY 0.510638 (-2295 2200);
FORCEPROP 1 LASTPIN (-2250 2175) $PN 1
J 2
(-2255 2137);
DISPLAY 0.787234 (-2255 2137);
FORCEPROP 1 LASTPIN (-2250 1975) $PN 2
J 2
(-2255 1985);
DISPLAY 0.787234 (-2255 1985);
FORCEPROP 2 LAST CDS_LIB pure_quanta
J 2
(-2250 2075);
PAINT MONO (-2250 2075);
DISPLAY INVISIBLE (-2250 2075);
FORCEPROP 1 LAST PATH I18
J 2
(-2300 2250);
DISPLAY 0.978723 (-2300 2250);
PAINT WHITE (-2300 2250);
DISPLAY INVISIBLE (-2300 2250);
FORCEPROP 2 LAST CDS_LOCATION R1688
J 2
(-2300 2300);
DISPLAY 1.021277 (-2300 2300);
DISPLAY INVISIBLE (-2300 2300);
FORCEPROP 2 LAST $SEC 1
J 2
(-2300 2300);
DISPLAY 0.680851 (-2300 2300);
PAINT MONO (-2300 2300);
DISPLAY INVISIBLE (-2300 2300);
FORCEPROP 2 LAST CDS_SEC 1
J 2
(-2300 2300);
DISPLAY 1.021277 (-2300 2300);
DISPLAY INVISIBLE (-2300 2300);
FORCEADD UNIVERSAL_POWER..1
(-2250 2400);
FORCEPROP 3 LASTPIN (-2250 2350) SIG_NAME P12V_AUX\g
J 0
(-2240 2360);
DISPLAY 0.659574 (-2240 2360);
PAINT MONO (-2240 2360);
DISPLAY INVISIBLE (-2240 2360);
FORCEPROP 1 LAST HDL_POWER P12V_AUX
J 1
(-2250 2450);
DISPLAY 0.872340 (-2250 2450);
PAINT GREEN (-2250 2450);
FORCEPROP 2 LAST CDS_LIB logical_power
J 0
(-2250 2400);
PAINT MONO (-2250 2400);
DISPLAY INVISIBLE (-2250 2400);
FORCEPROP 1 LAST PATH I19
J 0
(-2200 2425);
DISPLAY 0.872340 (-2200 2425);
PAINT AQUA (-2200 2425);
DISPLAY INVISIBLE (-2200 2425);
FORCEADD UNIVERSAL_GND..1
(-2175 -2775);
FORCEPROP 3 LASTPIN (-2175 -2725) SIG_NAME GND\g
J 0
(-2165 -2715);
DISPLAY 0.659574 (-2165 -2715);
PAINT MONO (-2165 -2715);
DISPLAY INVISIBLE (-2165 -2715);
FORCEPROP 1 LAST HDL_POWER GND
J 1
(-2150 -2850);
DISPLAY 0.872340 (-2150 -2850);
PAINT GREEN (-2150 -2850);
DISPLAY INVISIBLE (-2150 -2850);
FORCEPROP 2 LAST CDS_LIB logical_power
J 0
(-2175 -2775);
PAINT MONO (-2175 -2775);
DISPLAY INVISIBLE (-2175 -2775);
FORCEPROP 1 LAST PATH I2
J 0
(-2100 -2775);
DISPLAY 0.872340 (-2100 -2775);
PAINT AQUA (-2100 -2775);
DISPLAY INVISIBLE (-2100 -2775);
FORCEADD Q_RES..1
(-1600 175);
FORCEPROP 1 LAST PART_NUMBER CS00002JB13
J 0
(-1700 225);
DISPLAY 0.404255 (-1700 225);
DISPLAY INVISIBLE (-1700 225);
FORCEPROP 1 LAST WATTAGE 1/16W
J 2
(-1475 250);
DISPLAY 0.404255 (-1475 250);
FORCEPROP 1 LAST MATERIAL CHIP
J 0
(-1375 175);
DISPLAY 0.404255 (-1375 175);
FORCEPROP 1 LAST VALUE 0
J 2
(-1475 175);
DISPLAY 0.404255 (-1475 175);
FORCEPROP 1 LAST TOLERANCE 5%
J 0
(-1450 175);
DISPLAY 0.404255 (-1450 175);
FORCEPROP 1 LAST PACK_TYPE 0402LF
J 0
(-1700 250);
DISPLAY 0.404255 (-1700 250);
FORCEPROP 1 LAST $LOCATION R1950
J 0
(-1825 175);
DISPLAY 0.510638 (-1825 175);
FORCEPROP 1 LASTPIN (-1700 175) $PN 1
J 0
(-1688 187);
DISPLAY 0.787234 (-1688 187);
PAINT MONO (-1688 187);
FORCEPROP 1 LASTPIN (-1500 175) $PN 2
J 0
(-1538 187);
DISPLAY 0.787234 (-1538 187);
PAINT MONO (-1538 187);
FORCEPROP 2 LAST CDS_LIB pure_quanta
J 0
(-1600 175);
DISPLAY INVISIBLE (-1600 175);
FORCEPROP 1 LAST PATH I20
J 0
(-1650 325);
DISPLAY 0.978723 (-1650 325);
PAINT WHITE (-1650 325);
DISPLAY INVISIBLE (-1650 325);
FORCEPROP 0 LAST CDS_LOCATION R1950
J 0
(-1475 275);
DISPLAY 1.021277 (-1475 275);
DISPLAY INVISIBLE (-1475 275);
FORCEPROP 0 LAST $SEC 1
J 0
(-1475 275);
DISPLAY 0.680851 (-1475 275);
PAINT MONO (-1475 275);
DISPLAY INVISIBLE (-1475 275);
FORCEPROP 0 LAST CDS_SEC 1
J 0
(-1475 275);
DISPLAY 1.021277 (-1475 275);
DISPLAY INVISIBLE (-1475 275);
FORCEADD Q_RES..1
(-1600 425);
FORCEPROP 1 LAST PART_NUMBER CS00002JB13
J 0
(-1700 475);
DISPLAY 0.404255 (-1700 475);
DISPLAY INVISIBLE (-1700 475);
FORCEPROP 1 LAST PACK_TYPE 0402LF
J 0
(-1700 500);
DISPLAY 0.404255 (-1700 500);
FORCEPROP 1 LAST VALUE 0
J 2
(-1475 425);
DISPLAY 0.404255 (-1475 425);
FORCEPROP 1 LAST TOLERANCE 5%
J 0
(-1450 425);
DISPLAY 0.404255 (-1450 425);
FORCEPROP 1 LAST MATERIAL EMPTY
J 0
(-1375 425);
DISPLAY 0.404255 (-1375 425);
PAINT RED (-1375 425);
FORCEPROP 1 LAST WATTAGE 1/16W
J 2
(-1475 500);
DISPLAY 0.404255 (-1475 500);
FORCEPROP 1 LAST $LOCATION R1745
J 0
(-1825 425);
DISPLAY 0.510638 (-1825 425);
FORCEPROP 1 LASTPIN (-1700 425) $PN 1
J 0
(-1688 437);
DISPLAY 0.787234 (-1688 437);
FORCEPROP 1 LASTPIN (-1500 425) $PN 2
J 0
(-1538 437);
DISPLAY 0.787234 (-1538 437);
FORCEPROP 2 LAST CDS_LIB pure_quanta
J 0
(-1600 425);
PAINT MONO (-1600 425);
DISPLAY INVISIBLE (-1600 425);
FORCEPROP 1 LAST PATH I21
J 0
(-1650 575);
DISPLAY 0.978723 (-1650 575);
PAINT WHITE (-1650 575);
DISPLAY INVISIBLE (-1650 575);
FORCEPROP 2 LAST CDS_LOCATION R1745
J 0
(-1650 625);
DISPLAY 1.021277 (-1650 625);
DISPLAY INVISIBLE (-1650 625);
FORCEPROP 2 LAST $SEC 1
J 0
(-1650 625);
DISPLAY 0.680851 (-1650 625);
PAINT MONO (-1650 625);
DISPLAY INVISIBLE (-1650 625);
FORCEPROP 2 LAST CDS_SEC 1
J 0
(-1650 625);
DISPLAY 1.021277 (-1650 625);
DISPLAY INVISIBLE (-1650 625);
FORCEADD Q_RES..2
(-1850 2075);
FORCEPROP 1 LAST PART_NUMBER CS31002FB08
J 0
(-1810 1950);
DISPLAY 0.404255 (-1810 1950);
DISPLAY INVISIBLE (-1810 1950);
FORCEPROP 1 LAST VALUE 10K
J 0
(-1805 2150);
DISPLAY 0.510638 (-1805 2150);
FORCEPROP 1 LAST TOLERANCE 1%
J 0
(-1805 2100);
DISPLAY 0.510638 (-1805 2100);
FORCEPROP 1 LAST WATTAGE 1/16W
J 0
(-1810 2050);
DISPLAY 0.510638 (-1810 2050);
FORCEPROP 1 LAST MATERIAL CHIP
J 0
(-1810 2000);
DISPLAY 0.510638 (-1810 2000);
FORCEPROP 1 LAST PACK_TYPE 0402LF
J 0
(-1810 1900);
DISPLAY 0.510638 (-1810 1900);
FORCEPROP 1 LAST $LOCATION R1690
J 0
(-1805 2200);
DISPLAY 0.510638 (-1805 2200);
FORCEPROP 1 LASTPIN (-1850 2175) $PN 1
J 0
(-1845 2137);
DISPLAY 0.787234 (-1845 2137);
FORCEPROP 1 LASTPIN (-1850 1975) $PN 2
J 0
(-1845 1985);
DISPLAY 0.787234 (-1845 1985);
FORCEPROP 2 LAST CDS_LIB pure_quanta
J 0
(-1850 2075);
PAINT MONO (-1850 2075);
DISPLAY INVISIBLE (-1850 2075);
FORCEPROP 1 LAST PATH I22
J 0
(-1800 2250);
DISPLAY 0.978723 (-1800 2250);
PAINT WHITE (-1800 2250);
DISPLAY INVISIBLE (-1800 2250);
FORCEPROP 2 LAST CDS_LOCATION R1690
J 0
(-1800 2300);
DISPLAY 1.021277 (-1800 2300);
DISPLAY INVISIBLE (-1800 2300);
FORCEPROP 2 LAST $SEC 1
J 0
(-1800 2300);
DISPLAY 0.680851 (-1800 2300);
PAINT MONO (-1800 2300);
DISPLAY INVISIBLE (-1800 2300);
FORCEPROP 2 LAST CDS_SEC 1
J 0
(-1800 2300);
DISPLAY 1.021277 (-1800 2300);
DISPLAY INVISIBLE (-1800 2300);
FORCEADD UNIVERSAL_GND..1
(-850 1900);
FORCEPROP 3 LASTPIN (-850 1950) SIG_NAME GND\g
J 0
(-840 1960);
DISPLAY 0.659574 (-840 1960);
PAINT MONO (-840 1960);
DISPLAY INVISIBLE (-840 1960);
FORCEPROP 1 LAST HDL_POWER GND
J 1
(-825 1825);
DISPLAY 0.872340 (-825 1825);
PAINT GREEN (-825 1825);
DISPLAY INVISIBLE (-825 1825);
FORCEPROP 2 LAST CDS_LIB logical_power
J 0
(-850 1900);
PAINT MONO (-850 1900);
DISPLAY INVISIBLE (-850 1900);
FORCEPROP 1 LAST PATH I23
J 0
(-775 1900);
DISPLAY 0.872340 (-775 1900);
PAINT AQUA (-775 1900);
DISPLAY INVISIBLE (-775 1900);
FORCEADD Q_CAP..1
R 2
(-850 2100);
FORCEPROP 1 LAST PART_NUMBER CH5104KEB02
J 2
(-900 1950);
DISPLAY 0.510638 (-900 1950);
DISPLAY INVISIBLE (-900 1950);
FORCEPROP 1 LAST VOLTAGE 25V
J 2
(-900 2100);
DISPLAY 0.510638 (-900 2100);
FORCEPROP 1 LAST MATERIAL X6S
J 2
(-900 2000);
DISPLAY 0.510638 (-900 2000);
FORCEPROP 1 LAST TOLERANCE 10%
J 2
(-900 2050);
DISPLAY 0.510638 (-900 2050);
FORCEPROP 1 LAST PACK_TYPE C0402
J 2
(-900 1900);
DISPLAY 0.510638 (-900 1900);
FORCEPROP 1 LAST VALUE 1UF
J 2
(-900 2150);
DISPLAY 0.510638 (-900 2150);
FORCEPROP 1 LAST $LOCATION C1315
J 2
(-900 2200);
DISPLAY 0.510638 (-900 2200);
FORCEPROP 1 LASTPIN (-850 2200) $PN 1
J 2
(-860 2180);
DISPLAY 0.787234 (-860 2180);
FORCEPROP 1 LASTPIN (-850 2000) $PN 2
J 2
(-860 1980);
DISPLAY 0.787234 (-860 1980);
FORCEPROP 2 LAST CDS_LIB pure_quanta
J 2
(-850 2100);
PAINT MONO (-850 2100);
DISPLAY INVISIBLE (-850 2100);
FORCEPROP 1 LAST PATH I24
J 2
(-900 2250);
DISPLAY 0.978723 (-900 2250);
PAINT WHITE (-900 2250);
DISPLAY INVISIBLE (-900 2250);
FORCEPROP 2 LAST CDS_LOCATION C1315
J 0
(-900 2300);
DISPLAY 1.021277 (-900 2300);
DISPLAY INVISIBLE (-900 2300);
FORCEPROP 2 LAST $SEC 1
J 0
(-900 2300);
DISPLAY 0.680851 (-900 2300);
PAINT MONO (-900 2300);
DISPLAY INVISIBLE (-900 2300);
FORCEPROP 2 LAST CDS_SEC 1
J 0
(-900 2300);
DISPLAY 1.021277 (-900 2300);
DISPLAY INVISIBLE (-900 2300);
FORCEADD OFFPAGE..4
(-625 425);
FORCEPROP 2 LAST $XR0 214 
J 0
(-439 425);
DISPLAY 0.638298 (-439 425);
PAINT MONO (-439 425);
FORCEPROP 2 LAST $XR1 220 
J 0
(-319 425);
DISPLAY 0.638298 (-319 425);
PAINT MONO (-319 425);
FORCEPROP 2 LAST CDS_LIB standard
J 0
(-625 425);
PAINT MONO (-625 425);
DISPLAY INVISIBLE (-625 425);
FORCEPROP 1 LAST OFFPAGE TRUE
J 0
(-300 300);
DISPLAY 1.170213 (-300 300);
PAINT GREEN (-300 300);
DISPLAY INVISIBLE (-300 300);
FORCEPROP 1 LAST COMMENT_BODY TRUE
J 0
(-650 325);
DISPLAY 1.170213 (-650 325);
PAINT GREEN (-650 325);
DISPLAY INVISIBLE (-650 325);
FORCEPROP 2 LAST PATH I25
J 0
(-300 475);
DISPLAY 1.021277 (-300 475);
DISPLAY INVISIBLE (-300 475);
FORCEADD TPS3895ADRYR..1
(50 1150);
FORCEPROP 1 LAST PART_NUMBER AL003895003
J 0
(-225 1442);
DISPLAY 0.723404 (-225 1442);
PAINT GREEN (-225 1442);
DISPLAY INVISIBLE (-225 1442);
FORCEPROP 1 LAST MATERIAL EMPTY
J 0
(-220 1315);
DISPLAY 0.723404 (-220 1315);
PAINT GREEN (-220 1315);
FORCEPROP 2 LAST PART_TYPE SMLF
J 0
(-225 1586);
DISPLAY 1.021277 (-225 1586);
FORCEPROP 0 LAST ROOM DELAY1_BOM2
J 0
(-200 1375);
DISPLAY 1.021277 (-200 1375);
FORCEPROP 2 LAST VALUE TPS3895ADRYR
J 0
(-225 1536);
DISPLAY 1.021277 (-225 1536);
FORCEPROP 1 LAST LOCATION U117
J 0
(-225 1500);
DISPLAY 0.723404 (-225 1500);
PAINT GREEN (-225 1500);
FORCEPROP 0 LASTPIN (475 1150) $PN 5
J 0
(485 1160);
DISPLAY 0.680851 (485 1160);
PAINT MONO (485 1160);
FORCEPROP 0 LASTPIN (-375 1050) $PN 1
J 2
(-385 1060);
DISPLAY 0.680851 (-385 1060);
PAINT MONO (-385 1060);
FORCEPROP 0 LASTPIN (475 1050) $PN 2
J 0
(485 1060);
DISPLAY 0.680851 (485 1060);
PAINT MONO (485 1060);
FORCEPROP 0 LASTPIN (-375 1150) $PN 3
J 2
(-385 1160);
DISPLAY 0.680851 (-385 1160);
PAINT MONO (-385 1160);
FORCEPROP 0 LASTPIN (475 1250) $PN 4
J 0
(485 1260);
DISPLAY 0.680851 (485 1260);
PAINT MONO (485 1260);
FORCEPROP 0 LASTPIN (-375 1250) $PN 6
J 2
(-385 1260);
DISPLAY 0.680851 (-385 1260);
PAINT MONO (-385 1260);
FORCEPROP 1 LAST CDS_LMAN_SYM_OUTLINE -275,150,275,-150
J 0
(50 1150);
DISPLAY 0.468085 (50 1150);
PAINT GREEN (50 1150);
DISPLAY INVISIBLE (50 1150);
FORCEPROP 1 LAST NEEDS_NO_SIZE TRUE
J 0
(50 1150);
DISPLAY 0.723404 (50 1150);
PAINT GREEN (50 1150);
DISPLAY INVISIBLE (50 1150);
FORCEPROP 2 LAST CDS_LIB pure_quanta
J 0
(50 1150);
DISPLAY INVISIBLE (50 1150);
FORCEPROP 1 LAST PATH I26
J 0
(50 1150);
DISPLAY 0.723404 (50 1150);
PAINT GREEN (50 1150);
DISPLAY INVISIBLE (50 1150);
FORCEPROP 0 LAST $SEC 1
J 0
(-225 1650);
DISPLAY 0.680851 (-225 1650);
PAINT MONO (-225 1650);
DISPLAY INVISIBLE (-225 1650);
FORCEPROP 0 LAST CDS_SEC 1
J 0
(-225 1650);
DISPLAY 1.021277 (-225 1650);
DISPLAY INVISIBLE (-225 1650);
FORCEADD ADM1086AKSZREEL7..1
(75 1775);
FORCEPROP 1 LAST PART_NUMBER AL001086001
J 0
(-125 2025);
DISPLAY 0.723404 (-125 2025);
PAINT GREEN (-125 2025);
DISPLAY INVISIBLE (-125 2025);
FORCEPROP 2 LAST PART_TYPE SMLF
J 0
(-125 2225);
DISPLAY 0.638298 (-125 2225);
FORCEPROP 2 LAST VALUE ADM1086AKSZ-REEL7
J 0
(-125 2175);
DISPLAY 0.638298 (-125 2175);
FORCEPROP 1 LAST MATERIAL IC
J 0
(-125 1950);
DISPLAY 0.723404 (-125 1950);
PAINT GREEN (-125 1950);
FORCEPROP 0 LAST ROOM DELAY1_BOM1
J 0
(-125 2275);
DISPLAY 1.021277 (-125 2275);
FORCEPROP 1 LAST $LOCATION U94
J 0
(-125 2100);
DISPLAY 0.723404 (-125 2100);
PAINT GREEN (-125 2100);
FORCEPROP 0 LASTPIN (375 1775) $PN 5
J 0
(385 1785);
DISPLAY 0.808511 (385 1785);
PAINT MONO (385 1785);
FORCEPROP 0 LASTPIN (-275 1725) $PN 1
J 2
(-285 1735);
DISPLAY 0.808511 (-285 1735);
PAINT MONO (-285 1735);
FORCEPROP 0 LASTPIN (375 1875) $PN 4
J 0
(385 1885);
DISPLAY 0.808511 (385 1885);
PAINT MONO (385 1885);
FORCEPROP 0 LASTPIN (375 1725) $PN 2
J 0
(385 1735);
DISPLAY 0.808511 (385 1735);
PAINT MONO (385 1735);
FORCEPROP 0 LASTPIN (-275 1875) $PN 6
J 2
(-285 1885);
DISPLAY 0.808511 (-285 1885);
PAINT MONO (-285 1885);
FORCEPROP 0 LASTPIN (-275 1825) $PN 3
J 2
(-285 1835);
DISPLAY 0.808511 (-285 1835);
PAINT MONO (-285 1835);
FORCEPROP 1 LAST NEEDS_NO_SIZE TRUE
J 0
(75 1775);
DISPLAY 0.723404 (75 1775);
PAINT GREEN (75 1775);
DISPLAY INVISIBLE (75 1775);
FORCEPROP 1 LAST CDS_LMAN_SYM_OUTLINE -200,150,150,-100
J 0
(75 1775);
DISPLAY 0.468085 (75 1775);
PAINT GREEN (75 1775);
DISPLAY INVISIBLE (75 1775);
FORCEPROP 2 LAST CDS_LIB pure_quanta
J 0
(75 1775);
DISPLAY INVISIBLE (75 1775);
FORCEPROP 1 LAST PATH I27
J 0
(75 1775);
DISPLAY 0.723404 (75 1775);
PAINT GREEN (75 1775);
DISPLAY INVISIBLE (75 1775);
FORCEPROP 2 LAST CDS_LOCATION U94
J 0
(-100 2275);
DISPLAY 1.021277 (-100 2275);
DISPLAY INVISIBLE (-100 2275);
FORCEPROP 0 LAST $SEC 1
J 0
(-100 2275);
PAINT MONO (-100 2275);
DISPLAY INVISIBLE (-100 2275);
FORCEPROP 2 LAST CDS_SEC 1
J 0
(-100 2275);
DISPLAY 1.021277 (-100 2275);
DISPLAY INVISIBLE (-100 2275);
FORCEADD UNIVERSAL_POWER..1
(-1850 2400);
FORCEPROP 3 LASTPIN (-1850 2350) SIG_NAME P3V3_AUX\g
J 0
(-1840 2360);
DISPLAY 0.659574 (-1840 2360);
PAINT MONO (-1840 2360);
DISPLAY INVISIBLE (-1840 2360);
FORCEPROP 1 LAST HDL_POWER P3V3_AUX
J 1
(-1850 2450);
DISPLAY 0.872340 (-1850 2450);
PAINT GREEN (-1850 2450);
FORCEPROP 2 LAST CDS_LIB logical_power
J 0
(-1850 2400);
PAINT MONO (-1850 2400);
DISPLAY INVISIBLE (-1850 2400);
FORCEPROP 1 LAST PATH I28
J 0
(-1800 2425);
DISPLAY 0.872340 (-1800 2425);
PAINT AQUA (-1800 2425);
DISPLAY INVISIBLE (-1800 2425);
FORCEADD UNIVERSAL_POWER..1
(-475 2450);
FORCEPROP 3 LASTPIN (-475 2400) SIG_NAME P3V3_AUX\g
J 0
(-465 2410);
DISPLAY 0.659574 (-465 2410);
PAINT MONO (-465 2410);
DISPLAY INVISIBLE (-465 2410);
FORCEPROP 1 LAST HDL_POWER P3V3_AUX
J 1
(-475 2500);
DISPLAY 0.872340 (-475 2500);
PAINT GREEN (-475 2500);
FORCEPROP 2 LAST CDS_LIB logical_power
J 0
(-475 2450);
PAINT MONO (-475 2450);
DISPLAY INVISIBLE (-475 2450);
FORCEPROP 1 LAST PATH I29
J 0
(-425 2475);
DISPLAY 0.872340 (-425 2475);
PAINT AQUA (-425 2475);
DISPLAY INVISIBLE (-425 2475);
FORCEADD Q_RES..2
(-2175 -2550);
FORCEPROP 1 LAST PART_NUMBER CS41002FB09
J 0
(-2135 -2675);
DISPLAY 0.510638 (-2135 -2675);
DISPLAY INVISIBLE (-2135 -2675);
FORCEPROP 1 LAST MATERIAL CHIP
J 0
(-2135 -2625);
DISPLAY 0.510638 (-2135 -2625);
FORCEPROP 1 LAST WATTAGE 1/16W
J 0
(-2135 -2575);
DISPLAY 0.510638 (-2135 -2575);
FORCEPROP 1 LAST VALUE 100K
J 0
(-2130 -2475);
DISPLAY 0.510638 (-2130 -2475);
FORCEPROP 1 LAST TOLERANCE 1%
J 0
(-2130 -2525);
DISPLAY 0.510638 (-2130 -2525);
FORCEPROP 1 LAST PACK_TYPE 0402LF
J 0
(-2135 -2725);
DISPLAY 0.510638 (-2135 -2725);
FORCEPROP 1 LAST $LOCATION R1692
J 0
(-2130 -2425);
DISPLAY 0.510638 (-2130 -2425);
FORCEPROP 1 LASTPIN (-2175 -2450) $PN 1
J 0
(-2170 -2488);
DISPLAY 0.787234 (-2170 -2488);
FORCEPROP 1 LASTPIN (-2175 -2650) $PN 2
J 0
(-2170 -2640);
DISPLAY 0.787234 (-2170 -2640);
FORCEPROP 2 LAST CDS_LIB pure_quanta
J 0
(-2175 -2550);
PAINT MONO (-2175 -2550);
DISPLAY INVISIBLE (-2175 -2550);
FORCEPROP 1 LAST PATH I3
J 0
(-2125 -2375);
DISPLAY 0.978723 (-2125 -2375);
PAINT WHITE (-2125 -2375);
DISPLAY INVISIBLE (-2125 -2375);
FORCEPROP 2 LAST CDS_LOCATION R1692
J 0
(-2125 -2325);
DISPLAY 1.021277 (-2125 -2325);
DISPLAY INVISIBLE (-2125 -2325);
FORCEPROP 2 LAST $SEC 1
J 0
(-2125 -2325);
DISPLAY 0.680851 (-2125 -2325);
PAINT MONO (-2125 -2325);
DISPLAY INVISIBLE (-2125 -2325);
FORCEPROP 2 LAST CDS_SEC 1
J 0
(-2125 -2325);
DISPLAY 1.021277 (-2125 -2325);
DISPLAY INVISIBLE (-2125 -2325);
FORCEADD UNIVERSAL_GND..1
(675 -2825);
FORCEPROP 3 LASTPIN (675 -2775) SIG_NAME GND\g
J 0
(685 -2765);
DISPLAY 0.659574 (685 -2765);
PAINT MONO (685 -2765);
DISPLAY INVISIBLE (685 -2765);
FORCEPROP 2 LAST CDS_LIB logical_power
J 0
(675 -2825);
DISPLAY INVISIBLE (675 -2825);
FORCEPROP 1 LAST HDL_POWER GND
J 1
(700 -2900);
DISPLAY 0.872340 (700 -2900);
PAINT GREEN (700 -2900);
DISPLAY INVISIBLE (700 -2900);
FORCEPROP 1 LAST PATH I30
J 0
(750 -2825);
DISPLAY 0.872340 (750 -2825);
PAINT AQUA (750 -2825);
DISPLAY INVISIBLE (750 -2825);
FORCEADD Q_RES..2
(675 -2600);
FORCEPROP 1 LAST PART_NUMBER CS41002FB09
J 0
(715 -2725);
DISPLAY 0.510638 (715 -2725);
DISPLAY INVISIBLE (715 -2725);
FORCEPROP 1 LAST MATERIAL EMPTY
J 0
(715 -2675);
DISPLAY 0.510638 (715 -2675);
FORCEPROP 1 LAST PACK_TYPE 0402LF
J 0
(715 -2775);
DISPLAY 0.510638 (715 -2775);
FORCEPROP 1 LAST VALUE 100K
J 0
(720 -2525);
DISPLAY 0.510638 (720 -2525);
FORCEPROP 1 LAST TOLERANCE 1%
J 0
(720 -2575);
DISPLAY 0.510638 (720 -2575);
FORCEPROP 1 LAST WATTAGE 1/16W
J 0
(715 -2625);
DISPLAY 0.510638 (715 -2625);
FORCEPROP 1 LAST $LOCATION R4808
J 0
(720 -2475);
DISPLAY 0.978723 (720 -2475);
FORCEPROP 1 LASTPIN (675 -2500) $PN 1
J 0
(680 -2538);
DISPLAY 0.787234 (680 -2538);
PAINT MONO (680 -2538);
FORCEPROP 1 LASTPIN (675 -2700) $PN 2
J 0
(680 -2690);
DISPLAY 0.787234 (680 -2690);
PAINT MONO (680 -2690);
FORCEPROP 2 LAST CDS_LIB pure_quanta
J 0
(675 -2600);
DISPLAY INVISIBLE (675 -2600);
FORCEPROP 1 LAST PATH I31
J 0
(725 -2425);
DISPLAY 0.978723 (725 -2425);
PAINT WHITE (725 -2425);
DISPLAY INVISIBLE (725 -2425);
FORCEPROP 0 LAST CDS_LOCATION R4808
J 0
(725 -2425);
DISPLAY 1.021277 (725 -2425);
DISPLAY INVISIBLE (725 -2425);
FORCEPROP 0 LAST $SEC 1
J 0
(725 -2425);
DISPLAY 0.680851 (725 -2425);
PAINT MONO (725 -2425);
DISPLAY INVISIBLE (725 -2425);
FORCEPROP 0 LAST CDS_SEC 1
J 0
(725 -2425);
DISPLAY 1.021277 (725 -2425);
DISPLAY INVISIBLE (725 -2425);
FORCEADD Q_RES..1
(400 -2300);
FORCEPROP 1 LAST PART_NUMBER CS03322FB03
J 0
(275 -2250);
DISPLAY 0.404255 (275 -2250);
DISPLAY INVISIBLE (275 -2250);
FORCEPROP 1 LAST VALUE 33.2
J 2
(600 -2300);
DISPLAY 0.404255 (600 -2300);
FORCEPROP 1 LAST WATTAGE 1/16W
J 2
(525 -2200);
DISPLAY 0.404255 (525 -2200);
FORCEPROP 1 LAST MATERIAL CHIP
J 0
(675 -2300);
DISPLAY 0.404255 (675 -2300);
FORCEPROP 1 LAST TOLERANCE 1%
J 0
(625 -2300);
DISPLAY 0.404255 (625 -2300);
FORCEPROP 1 LAST PACK_TYPE 0402LF
J 0
(275 -2200);
DISPLAY 0.404255 (275 -2200);
FORCEPROP 1 LAST $LOCATION R1693
J 0
(100 -2300);
DISPLAY 0.638298 (100 -2300);
FORCEPROP 1 LASTPIN (300 -2300) $PN 1
J 0
(312 -2288);
DISPLAY 0.787234 (312 -2288);
FORCEPROP 1 LASTPIN (500 -2300) $PN 2
J 0
(462 -2288);
DISPLAY 0.787234 (462 -2288);
FORCEPROP 2 LAST CDS_LIB pure_quanta
J 0
(400 -2300);
PAINT MONO (400 -2300);
DISPLAY INVISIBLE (400 -2300);
FORCEPROP 1 LAST PATH I32
J 0
(350 -2150);
DISPLAY 0.978723 (350 -2150);
PAINT WHITE (350 -2150);
DISPLAY INVISIBLE (350 -2150);
FORCEPROP 2 LAST CDS_LOCATION R1693
J 0
(350 -2100);
DISPLAY 1.021277 (350 -2100);
DISPLAY INVISIBLE (350 -2100);
FORCEPROP 2 LAST $SEC 1
J 0
(350 -2100);
DISPLAY 0.680851 (350 -2100);
PAINT MONO (350 -2100);
DISPLAY INVISIBLE (350 -2100);
FORCEPROP 2 LAST CDS_SEC 1
J 0
(350 -2100);
DISPLAY 1.021277 (350 -2100);
DISPLAY INVISIBLE (350 -2100);
FORCEADD Q_RES..2
R 2
(975 -1975);
FORCEPROP 1 LAST PART_NUMBER CS31002FB08
J 2
(935 -2100);
DISPLAY 0.510638 (935 -2100);
DISPLAY INVISIBLE (935 -2100);
FORCEPROP 1 LAST PACK_TYPE 0402LF
J 2
(935 -2150);
DISPLAY 0.510638 (935 -2150);
FORCEPROP 1 LAST MATERIAL CHIP
J 2
(935 -2050);
DISPLAY 0.510638 (935 -2050);
FORCEPROP 1 LAST WATTAGE 1/16W
J 2
(935 -2000);
DISPLAY 0.510638 (935 -2000);
FORCEPROP 1 LAST TOLERANCE 1%
J 2
(930 -1950);
DISPLAY 0.510638 (930 -1950);
FORCEPROP 1 LAST VALUE 10K
J 2
(930 -1900);
DISPLAY 0.510638 (930 -1900);
FORCEPROP 1 LAST $LOCATION R1694
J 2
(930 -1850);
DISPLAY 0.638298 (930 -1850);
FORCEPROP 1 LASTPIN (975 -1875) $PN 1
J 2
(970 -1913);
DISPLAY 0.787234 (970 -1913);
FORCEPROP 1 LASTPIN (975 -2075) $PN 2
J 2
(970 -2065);
DISPLAY 0.787234 (970 -2065);
FORCEPROP 2 LAST CDS_LIB pure_quanta
J 2
(975 -1975);
PAINT MONO (975 -1975);
DISPLAY INVISIBLE (975 -1975);
FORCEPROP 1 LAST PATH I33
J 2
(925 -1800);
DISPLAY 0.978723 (925 -1800);
PAINT WHITE (925 -1800);
DISPLAY INVISIBLE (925 -1800);
FORCEPROP 2 LAST CDS_LOCATION R1694
J 0
(925 -1750);
DISPLAY 1.021277 (925 -1750);
DISPLAY INVISIBLE (925 -1750);
FORCEPROP 2 LAST $SEC 1
J 0
(925 -1750);
DISPLAY 0.680851 (925 -1750);
PAINT MONO (925 -1750);
DISPLAY INVISIBLE (925 -1750);
FORCEPROP 2 LAST CDS_SEC 1
J 0
(925 -1750);
DISPLAY 1.021277 (925 -1750);
DISPLAY INVISIBLE (925 -1750);
FORCEADD UNIVERSAL_GND..1
(1325 -2825);
FORCEPROP 3 LASTPIN (1325 -2775) SIG_NAME GND\g
J 0
(1335 -2765);
DISPLAY 0.659574 (1335 -2765);
PAINT MONO (1335 -2765);
DISPLAY INVISIBLE (1335 -2765);
FORCEPROP 2 LAST CDS_LIB logical_power
J 0
(1325 -2825);
PAINT MONO (1325 -2825);
DISPLAY INVISIBLE (1325 -2825);
FORCEPROP 1 LAST HDL_POWER GND
J 1
(1350 -2900);
DISPLAY 0.872340 (1350 -2900);
PAINT GREEN (1350 -2900);
DISPLAY INVISIBLE (1350 -2900);
FORCEPROP 1 LAST PATH I34
J 0
(1400 -2825);
DISPLAY 0.872340 (1400 -2825);
PAINT AQUA (1400 -2825);
DISPLAY INVISIBLE (1400 -2825);
FORCEADD Q_CAP..1
R 2
(1325 -2525);
FORCEPROP 1 LAST PART_NUMBER CH5104KEB02
J 2
(1275 -2675);
DISPLAY 0.510638 (1275 -2675);
DISPLAY INVISIBLE (1275 -2675);
FORCEPROP 1 LAST PACK_TYPE C0402
J 2
(1275 -2725);
DISPLAY 0.510638 (1275 -2725);
FORCEPROP 1 LAST VALUE 1UF
J 2
(1275 -2475);
DISPLAY 0.510638 (1275 -2475);
FORCEPROP 1 LAST VOLTAGE 25V
J 2
(1275 -2525);
DISPLAY 0.510638 (1275 -2525);
FORCEPROP 1 LAST MATERIAL X6S
J 2
(1275 -2625);
DISPLAY 0.510638 (1275 -2625);
FORCEPROP 1 LAST TOLERANCE 10%
J 2
(1275 -2575);
DISPLAY 0.510638 (1275 -2575);
FORCEPROP 1 LAST $LOCATION C1319
J 2
(1275 -2425);
DISPLAY 0.638298 (1275 -2425);
FORCEPROP 1 LASTPIN (1325 -2425) $PN 1
J 2
(1315 -2445);
DISPLAY 0.787234 (1315 -2445);
FORCEPROP 1 LASTPIN (1325 -2625) $PN 2
J 2
(1315 -2645);
DISPLAY 0.787234 (1315 -2645);
FORCEPROP 2 LAST CDS_LIB pure_quanta
J 0
(1325 -2525);
PAINT MONO (1325 -2525);
DISPLAY INVISIBLE (1325 -2525);
FORCEPROP 1 LAST PATH I35
J 2
(1275 -2375);
DISPLAY 0.978723 (1275 -2375);
PAINT WHITE (1275 -2375);
DISPLAY INVISIBLE (1275 -2375);
FORCEPROP 2 LAST CDS_LOCATION C1319
J 0
(1275 -2325);
DISPLAY 1.021277 (1275 -2325);
DISPLAY INVISIBLE (1275 -2325);
FORCEPROP 2 LAST $SEC 1
J 0
(1275 -2325);
DISPLAY 0.680851 (1275 -2325);
PAINT MONO (1275 -2325);
DISPLAY INVISIBLE (1275 -2325);
FORCEPROP 2 LAST CDS_SEC 1
J 0
(1275 -2325);
DISPLAY 1.021277 (1275 -2325);
DISPLAY INVISIBLE (1275 -2325);
FORCEADD Q_RES..2
(1600 -2525);
FORCEPROP 1 LAST PART_NUMBER CS00002JB13
J 0
(1640 -2650);
DISPLAY 0.510638 (1640 -2650);
DISPLAY INVISIBLE (1640 -2650);
FORCEPROP 1 LAST VALUE 0
J 0
(1645 -2450);
DISPLAY 0.510638 (1645 -2450);
FORCEPROP 1 LAST MATERIAL EMPTY
J 0
(1640 -2600);
DISPLAY 0.510638 (1640 -2600);
PAINT RED (1640 -2600);
FORCEPROP 1 LAST WATTAGE 1/16W
J 0
(1640 -2550);
DISPLAY 0.510638 (1640 -2550);
FORCEPROP 1 LAST TOLERANCE 5%
J 0
(1645 -2500);
DISPLAY 0.510638 (1645 -2500);
FORCEPROP 1 LAST PACK_TYPE 0402LF
J 0
(1640 -2700);
DISPLAY 0.510638 (1640 -2700);
FORCEPROP 1 LAST $LOCATION R1695
J 0
(1645 -2400);
DISPLAY 0.638298 (1645 -2400);
FORCEPROP 1 LASTPIN (1600 -2425) $PN 1
J 0
(1605 -2463);
DISPLAY 0.787234 (1605 -2463);
FORCEPROP 1 LASTPIN (1600 -2625) $PN 2
J 0
(1605 -2615);
DISPLAY 0.787234 (1605 -2615);
FORCEPROP 2 LAST CDS_LIB pure_quanta
J 0
(1600 -2525);
PAINT MONO (1600 -2525);
DISPLAY INVISIBLE (1600 -2525);
FORCEPROP 1 LAST PATH I36
J 0
(1650 -2350);
DISPLAY 0.978723 (1650 -2350);
PAINT WHITE (1650 -2350);
DISPLAY INVISIBLE (1650 -2350);
FORCEPROP 2 LAST CDS_LOCATION R1695
J 0
(1650 -2300);
DISPLAY 1.021277 (1650 -2300);
DISPLAY INVISIBLE (1650 -2300);
FORCEPROP 2 LAST $SEC 1
J 0
(1650 -2300);
DISPLAY 0.680851 (1650 -2300);
PAINT MONO (1650 -2300);
DISPLAY INVISIBLE (1650 -2300);
FORCEPROP 2 LAST CDS_SEC 1
J 0
(1650 -2300);
DISPLAY 1.021277 (1650 -2300);
DISPLAY INVISIBLE (1650 -2300);
FORCEADD UNIVERSAL_POWER..1
(975 -1725);
FORCEPROP 3 LASTPIN (975 -1775) SIG_NAME P3V3_AUX\g
J 0
(985 -1765);
DISPLAY 0.659574 (985 -1765);
PAINT MONO (985 -1765);
DISPLAY INVISIBLE (985 -1765);
FORCEPROP 1 LAST HDL_POWER P3V3_AUX
J 1
(975 -1675);
DISPLAY 0.872340 (975 -1675);
PAINT GREEN (975 -1675);
FORCEPROP 2 LAST CDS_LIB logical_power
J 0
(975 -1725);
PAINT MONO (975 -1725);
DISPLAY INVISIBLE (975 -1725);
FORCEPROP 1 LAST PATH I37
J 0
(1025 -1700);
DISPLAY 0.872340 (1025 -1700);
PAINT AQUA (1025 -1700);
DISPLAY INVISIBLE (1025 -1700);
FORCEADD UNIVERSAL_GND..1
(875 -1050);
FORCEPROP 3 LASTPIN (875 -1000) SIG_NAME GND\g
J 0
(885 -990);
DISPLAY 0.659574 (885 -990);
PAINT MONO (885 -990);
DISPLAY INVISIBLE (885 -990);
FORCEPROP 2 LAST CDS_LIB logical_power
J 0
(875 -1050);
PAINT MONO (875 -1050);
DISPLAY INVISIBLE (875 -1050);
FORCEPROP 1 LAST HDL_POWER GND
J 1
(900 -1125);
DISPLAY 0.872340 (900 -1125);
PAINT GREEN (900 -1125);
DISPLAY INVISIBLE (900 -1125);
FORCEPROP 1 LAST PATH I38
J 0
(950 -1050);
DISPLAY 0.872340 (950 -1050);
PAINT AQUA (950 -1050);
DISPLAY INVISIBLE (950 -1050);
FORCEADD MOSFET_NCH_GDS_ESD_PROTECTED..1
R 2
(900 -650);
FORCEPROP 1 LAST PART_NUMBER BAM70020002
J 2
(758 -738);
DISPLAY 0.723404 (758 -738);
PAINT GREEN (758 -738);
DISPLAY INVISIBLE (758 -738);
FORCEPROP 1 LAST MATERIAL IC
J 2
(758 -795);
DISPLAY 0.723404 (758 -795);
PAINT GREEN (758 -795);
FORCEPROP 2 LAST VALUE 2N7002K
J 2
(750 -600);
DISPLAY 0.680851 (750 -600);
FORCEPROP 2 LAST PART_TYPE SMLF
J 2
(750 -550);
DISPLAY 0.680851 (750 -550);
FORCEPROP 1 LAST LOCATION Q53
J 2
(758 -686);
DISPLAY 0.723404 (758 -686);
PAINT GREEN (758 -686);
FORCEPROP 0 LASTPIN (875 -450) $PN D
R 1
J 0
(865 -440);
DISPLAY 0.680851 (865 -440);
PAINT MONO (865 -440);
FORCEPROP 0 LASTPIN (1075 -650) $PN G
J 0
(1085 -640);
DISPLAY 0.680851 (1085 -640);
PAINT MONO (1085 -640);
FORCEPROP 0 LASTPIN (875 -850) $PN S
R 1
J 2
(865 -860);
DISPLAY 0.680851 (865 -860);
PAINT MONO (865 -860);
FORCEPROP 1 LAST CDS_LMAN_SYM_OUTLINE -125,150,125,-150
J 2
(900 -650);
DISPLAY 0.468085 (900 -650);
PAINT GREEN (900 -650);
DISPLAY INVISIBLE (900 -650);
FORCEPROP 2 LAST CDS_LIB pure_quanta
J 2
(900 -650);
DISPLAY INVISIBLE (900 -650);
FORCEPROP 1 LAST NEEDS_NO_SIZE TRUE
J 2
(775 -760);
DISPLAY 0.723404 (775 -760);
PAINT GREEN (775 -760);
DISPLAY INVISIBLE (775 -760);
FORCEPROP 1 LAST PATH I39
J 2
(775 -800);
DISPLAY 0.723404 (775 -800);
PAINT GREEN (775 -800);
DISPLAY INVISIBLE (775 -800);
FORCEPROP 0 LAST $SEC 1
J 0
(750 -500);
DISPLAY 0.680851 (750 -500);
PAINT MONO (750 -500);
DISPLAY INVISIBLE (750 -500);
FORCEPROP 0 LAST CDS_SEC 1
J 0
(750 -500);
DISPLAY 1.021277 (750 -500);
DISPLAY INVISIBLE (750 -500);
FORCEADD Q_RES..2
(-2175 -2075);
FORCEPROP 1 LAST PART_NUMBER CS31002FB08
J 0
(-2135 -2200);
DISPLAY 0.510638 (-2135 -2200);
DISPLAY INVISIBLE (-2135 -2200);
FORCEPROP 1 LAST VALUE 10K
J 0
(-2130 -2000);
DISPLAY 0.510638 (-2130 -2000);
FORCEPROP 1 LAST TOLERANCE 1%
J 0
(-2130 -2050);
DISPLAY 0.510638 (-2130 -2050);
FORCEPROP 1 LAST WATTAGE 1/16W
J 0
(-2135 -2100);
DISPLAY 0.510638 (-2135 -2100);
FORCEPROP 1 LAST MATERIAL EMPTY
J 0
(-2135 -2150);
DISPLAY 0.510638 (-2135 -2150);
PAINT RED (-2135 -2150);
FORCEPROP 1 LAST PACK_TYPE 0402LF
J 0
(-2135 -2250);
DISPLAY 0.510638 (-2135 -2250);
FORCEPROP 1 LAST $LOCATION R1691
J 0
(-2130 -1950);
DISPLAY 0.638298 (-2130 -1950);
FORCEPROP 1 LASTPIN (-2175 -1975) $PN 1
J 0
(-2170 -2013);
DISPLAY 0.787234 (-2170 -2013);
FORCEPROP 1 LASTPIN (-2175 -2175) $PN 2
J 0
(-2170 -2165);
DISPLAY 0.787234 (-2170 -2165);
FORCEPROP 2 LAST CDS_LIB pure_quanta
J 0
(-2175 -2075);
PAINT MONO (-2175 -2075);
DISPLAY INVISIBLE (-2175 -2075);
FORCEPROP 1 LAST PATH I4
J 0
(-2125 -1900);
DISPLAY 0.978723 (-2125 -1900);
PAINT WHITE (-2125 -1900);
DISPLAY INVISIBLE (-2125 -1900);
FORCEPROP 2 LAST CDS_LOCATION R1691
J 0
(-2125 -1850);
DISPLAY 1.021277 (-2125 -1850);
DISPLAY INVISIBLE (-2125 -1850);
FORCEPROP 2 LAST $SEC 1
J 0
(-2125 -1850);
DISPLAY 0.680851 (-2125 -1850);
PAINT MONO (-2125 -1850);
DISPLAY INVISIBLE (-2125 -1850);
FORCEPROP 2 LAST CDS_SEC 1
J 0
(-2125 -1850);
DISPLAY 1.021277 (-2125 -1850);
DISPLAY INVISIBLE (-2125 -1850);
FORCEADD Q_RES..2
(875 -150);
FORCEPROP 1 LAST PART_NUMBER CS31002FB08
J 0
(915 -275);
DISPLAY 0.510638 (915 -275);
DISPLAY INVISIBLE (915 -275);
FORCEPROP 1 LAST PACK_TYPE 0402LF
J 0
(915 -325);
DISPLAY 0.510638 (915 -325);
FORCEPROP 1 LAST WATTAGE 1/16W
J 0
(915 -175);
DISPLAY 0.510638 (915 -175);
FORCEPROP 1 LAST MATERIAL CHIP
J 0
(915 -225);
DISPLAY 0.510638 (915 -225);
FORCEPROP 1 LAST VALUE 10K
J 0
(920 -75);
DISPLAY 0.510638 (920 -75);
FORCEPROP 1 LAST TOLERANCE 1%
J 0
(920 -125);
DISPLAY 0.510638 (920 -125);
FORCEPROP 1 LAST $LOCATION R2486
J 0
(920 -25);
DISPLAY 0.978723 (920 -25);
FORCEPROP 1 LASTPIN (875 -50) $PN 1
J 0
(880 -88);
DISPLAY 0.787234 (880 -88);
FORCEPROP 1 LASTPIN (875 -250) $PN 2
J 0
(880 -240);
DISPLAY 0.787234 (880 -240);
FORCEPROP 2 LAST CDS_LIB pure_quanta
J 0
(875 -150);
PAINT MONO (875 -150);
DISPLAY INVISIBLE (875 -150);
FORCEPROP 1 LAST PATH I40
J 0
(925 25);
DISPLAY 0.978723 (925 25);
PAINT WHITE (925 25);
DISPLAY INVISIBLE (925 25);
FORCEPROP 2 LAST CDS_LOCATION R2486
J 0
(925 75);
DISPLAY 1.021277 (925 75);
DISPLAY INVISIBLE (925 75);
FORCEPROP 2 LAST $SEC 1
J 0
(925 75);
DISPLAY 0.680851 (925 75);
PAINT MONO (925 75);
DISPLAY INVISIBLE (925 75);
FORCEPROP 2 LAST CDS_SEC 1
J 0
(925 75);
DISPLAY 1.021277 (925 75);
DISPLAY INVISIBLE (925 75);
FORCEADD UNIVERSAL_POWER..1
(875 100);
FORCEPROP 3 LASTPIN (875 50) SIG_NAME P3V3_AUX\g
J 0
(885 60);
DISPLAY 0.659574 (885 60);
PAINT MONO (885 60);
DISPLAY INVISIBLE (885 60);
FORCEPROP 1 LAST HDL_POWER P3V3_AUX
J 1
(875 150);
DISPLAY 0.872340 (875 150);
PAINT GREEN (875 150);
FORCEPROP 2 LAST CDS_LIB logical_power
J 0
(875 100);
PAINT MONO (875 100);
DISPLAY INVISIBLE (875 100);
FORCEPROP 1 LAST PATH I41
J 0
(925 125);
DISPLAY 0.872340 (925 125);
PAINT AQUA (925 125);
DISPLAY INVISIBLE (925 125);
FORCEADD OFFPAGE..4
(1850 -650);
FORCEPROP 2 LAST $XR0 259 
J 0
(2036 -650);
DISPLAY 0.638298 (2036 -650);
PAINT MONO (2036 -650);
FORCEPROP 2 LAST $XR1 222 
J 0
(2156 -650);
DISPLAY 0.638298 (2156 -650);
PAINT MONO (2156 -650);
FORCEPROP 2 LAST $XR2 258 
J 0
(2276 -650);
DISPLAY 0.638298 (2276 -650);
PAINT MONO (2276 -650);
FORCEPROP 2 LAST CDS_LIB standard
J 0
(1850 -650);
DISPLAY INVISIBLE (1850 -650);
FORCEPROP 2 LAST BOM_COST VR_SYSTEM 
J 0
(1600 -600);
DISPLAY 0.829787 (1600 -600);
PAINT PURPLE (1600 -600);
DISPLAY INVISIBLE (1600 -600);
FORCEPROP 1 LAST OFFPAGE TRUE
J 0
(2175 -775);
DISPLAY 0.872340 (2175 -775);
DISPLAY INVISIBLE (2175 -775);
FORCEPROP 1 LAST COMMENT_BODY TRUE
J 0
(1825 -750);
DISPLAY 0.872340 (1825 -750);
PAINT GREEN (1825 -750);
DISPLAY INVISIBLE (1825 -750);
FORCEPROP 2 LAST PATH I42
J 0
(2300 -600);
DISPLAY 1.021277 (2300 -600);
DISPLAY INVISIBLE (2300 -600);
FORCEADD OFFPAGE..2
(2275 -2775);
FORCEPROP 2 LAST $XR2 182 
J 0
(2704 -2775);
DISPLAY 0.638298 (2704 -2775);
PAINT MONO (2704 -2775);
FORCEPROP 2 LAST $XR1 131 
J 0
(2584 -2775);
DISPLAY 0.638298 (2584 -2775);
PAINT MONO (2584 -2775);
FORCEPROP 2 LAST $XR0 223 
J 0
(2464 -2775);
DISPLAY 0.638298 (2464 -2775);
PAINT MONO (2464 -2775);
FORCEPROP 2 LAST BOM_COST VR_SYSTEM 
J 0
(2025 -2725);
DISPLAY 0.829787 (2025 -2725);
PAINT PURPLE (2025 -2725);
DISPLAY INVISIBLE (2025 -2725);
FORCEPROP 1 LAST COMMENT_BODY TRUE
J 0
(2230 -2870);
DISPLAY 0.872340 (2230 -2870);
PAINT GREEN (2230 -2870);
DISPLAY INVISIBLE (2230 -2870);
FORCEPROP 1 LAST OFFPAGE TRUE
J 0
(2600 -2900);
DISPLAY 0.872340 (2600 -2900);
PAINT GREEN (2600 -2900);
DISPLAY INVISIBLE (2600 -2900);
FORCEPROP 2 LAST CDS_LIB standard
J 0
(2275 -2775);
PAINT MONO (2275 -2775);
DISPLAY INVISIBLE (2275 -2775);
FORCEPROP 2 LAST PATH I43
J 0
(2725 -2725);
DISPLAY 1.021277 (2725 -2725);
DISPLAY INVISIBLE (2725 -2725);
FORCEADD OFFPAGE..2
(2300 -2300);
FORCEPROP 2 LAST $XR3 214 
J 0
(2849 -2300);
DISPLAY 0.638298 (2849 -2300);
PAINT MONO (2849 -2300);
FORCEPROP 2 LAST $XR2 182 
J 0
(2729 -2300);
DISPLAY 0.638298 (2729 -2300);
PAINT MONO (2729 -2300);
FORCEPROP 2 LAST $XR1 307 
J 0
(2609 -2300);
DISPLAY 0.638298 (2609 -2300);
PAINT MONO (2609 -2300);
FORCEPROP 2 LAST $XR0 306 
J 0
(2489 -2300);
DISPLAY 0.638298 (2489 -2300);
PAINT MONO (2489 -2300);
FORCEPROP 1 LAST OFFPAGE TRUE
J 0
(2625 -2425);
DISPLAY 0.872340 (2625 -2425);
PAINT GREEN (2625 -2425);
DISPLAY INVISIBLE (2625 -2425);
FORCEPROP 1 LAST COMMENT_BODY TRUE
J 0
(2255 -2395);
DISPLAY 0.872340 (2255 -2395);
PAINT GREEN (2255 -2395);
DISPLAY INVISIBLE (2255 -2395);
FORCEPROP 2 LAST BOM_COST VR_SYSTEM 
J 0
(2050 -2250);
DISPLAY 0.829787 (2050 -2250);
PAINT PURPLE (2050 -2250);
DISPLAY INVISIBLE (2050 -2250);
FORCEPROP 2 LAST CDS_LIB standard
J 0
(2300 -2300);
PAINT MONO (2300 -2300);
DISPLAY INVISIBLE (2300 -2300);
FORCEPROP 2 LAST PATH I44
J 0
(2850 -2250);
DISPLAY 1.021277 (2850 -2250);
DISPLAY INVISIBLE (2850 -2250);
FORCEADD UNIVERSAL_GND..1
(550 875);
FORCEPROP 3 LASTPIN (550 925) SIG_NAME GND\g
J 0
(560 935);
DISPLAY 0.659574 (560 935);
PAINT MONO (560 935);
DISPLAY INVISIBLE (560 935);
FORCEPROP 1 LAST HDL_POWER GND
J 1
(575 800);
DISPLAY 0.872340 (575 800);
PAINT GREEN (575 800);
DISPLAY INVISIBLE (575 800);
FORCEPROP 2 LAST CDS_LIB logical_power
J 0
(550 875);
DISPLAY INVISIBLE (550 875);
FORCEPROP 1 LAST PATH I45
J 0
(625 875);
DISPLAY 0.872340 (625 875);
PAINT AQUA (625 875);
DISPLAY INVISIBLE (625 875);
FORCEADD UNIVERSAL_GND..1
(1425 675);
FORCEPROP 3 LASTPIN (1425 725) SIG_NAME GND\g
J 0
(1435 735);
DISPLAY 0.659574 (1435 735);
PAINT MONO (1435 735);
DISPLAY INVISIBLE (1435 735);
FORCEPROP 2 LAST CDS_LIB logical_power
J 0
(1425 675);
PAINT MONO (1425 675);
DISPLAY INVISIBLE (1425 675);
FORCEPROP 1 LAST HDL_POWER GND
J 1
(1450 600);
DISPLAY 0.872340 (1450 600);
PAINT GREEN (1450 600);
DISPLAY INVISIBLE (1450 600);
FORCEPROP 1 LAST PATH I46
J 0
(1500 675);
DISPLAY 0.872340 (1500 675);
PAINT AQUA (1500 675);
DISPLAY INVISIBLE (1500 675);
FORCEADD Q_CAP..1
(1425 900);
FORCEPROP 1 LAST PART_NUMBER CH3474K1B04
J 0
(1475 750);
DISPLAY 0.510638 (1475 750);
DISPLAY INVISIBLE (1475 750);
FORCEPROP 1 LAST MATERIAL X7R
J 0
(1475 800);
DISPLAY 0.510638 (1475 800);
FORCEPROP 1 LAST TOLERANCE 10%
J 0
(1475 850);
DISPLAY 0.510638 (1475 850);
FORCEPROP 1 LAST VOLTAGE 25V
J 0
(1475 900);
DISPLAY 0.510638 (1475 900);
FORCEPROP 1 LAST VALUE 0.047UF
J 0
(1475 950);
DISPLAY 0.510638 (1475 950);
FORCEPROP 1 LAST PACK_TYPE C0402
J 0
(1475 700);
DISPLAY 0.510638 (1475 700);
FORCEPROP 1 LAST $LOCATION C1316
J 0
(1475 1000);
DISPLAY 0.638298 (1475 1000);
FORCEPROP 1 LASTPIN (1425 1000) $PN 1
J 0
(1435 980);
DISPLAY 0.787234 (1435 980);
FORCEPROP 1 LASTPIN (1425 800) $PN 2
J 0
(1435 780);
DISPLAY 0.787234 (1435 780);
FORCEPROP 2 LAST CDS_LIB pure_quanta
J 0
(1425 900);
PAINT MONO (1425 900);
DISPLAY INVISIBLE (1425 900);
FORCEPROP 1 LAST PATH I47
J 0
(1475 1050);
DISPLAY 0.978723 (1475 1050);
PAINT WHITE (1475 1050);
DISPLAY INVISIBLE (1475 1050);
FORCEPROP 2 LAST CDS_LOCATION C1316
J 0
(1475 1100);
DISPLAY 1.021277 (1475 1100);
DISPLAY INVISIBLE (1475 1100);
FORCEPROP 2 LAST $SEC 1
J 0
(1475 1100);
DISPLAY 0.680851 (1475 1100);
PAINT MONO (1475 1100);
DISPLAY INVISIBLE (1475 1100);
FORCEPROP 2 LAST CDS_SEC 1
J 0
(1475 1100);
DISPLAY 1.021277 (1475 1100);
DISPLAY INVISIBLE (1475 1100);
FORCEADD OFFPAGE..2
(1475 1875);
FORCEPROP 2 LAST $XR0 244 
J 0
(1664 1875);
DISPLAY 0.638298 (1664 1875);
PAINT MONO (1664 1875);
FORCEPROP 2 LAST BOM_COST VR_SYSTEM 
J 0
(1225 1925);
DISPLAY 0.829787 (1225 1925);
PAINT PURPLE (1225 1925);
DISPLAY INVISIBLE (1225 1925);
FORCEPROP 1 LAST COMMENT_BODY TRUE
J 0
(1430 1780);
DISPLAY 0.872340 (1430 1780);
PAINT GREEN (1430 1780);
DISPLAY INVISIBLE (1430 1780);
FORCEPROP 1 LAST OFFPAGE TRUE
J 0
(1800 1750);
DISPLAY 0.872340 (1800 1750);
PAINT GREEN (1800 1750);
DISPLAY INVISIBLE (1800 1750);
FORCEPROP 2 LAST CDS_LIB standard
J 0
(1475 1875);
DISPLAY INVISIBLE (1475 1875);
FORCEPROP 2 LAST PATH I48
J 0
(1675 1925);
DISPLAY 1.021277 (1675 1925);
DISPLAY INVISIBLE (1675 1925);
FORCEADD UNIVERSAL_POWER..1
(-2175 -1825);
FORCEPROP 3 LASTPIN (-2175 -1875) SIG_NAME P3V3_AUX\g
J 0
(-2165 -1865);
DISPLAY 0.659574 (-2165 -1865);
PAINT MONO (-2165 -1865);
DISPLAY INVISIBLE (-2165 -1865);
FORCEPROP 1 LAST HDL_POWER P3V3_AUX
J 1
(-2175 -1775);
DISPLAY 0.872340 (-2175 -1775);
PAINT GREEN (-2175 -1775);
FORCEPROP 2 LAST CDS_LIB logical_power
J 0
(-2175 -1825);
PAINT MONO (-2175 -1825);
DISPLAY INVISIBLE (-2175 -1825);
FORCEPROP 1 LAST PATH I5
J 0
(-2125 -1800);
DISPLAY 0.872340 (-2125 -1800);
PAINT AQUA (-2125 -1800);
DISPLAY INVISIBLE (-2125 -1800);
FORCEADD UNIVERSAL_GND..1
(-1375 -2725);
FORCEPROP 3 LASTPIN (-1375 -2675) SIG_NAME GND\g
J 0
(-1365 -2665);
DISPLAY 0.659574 (-1365 -2665);
PAINT MONO (-1365 -2665);
DISPLAY INVISIBLE (-1365 -2665);
FORCEPROP 1 LAST HDL_POWER GND
J 1
(-1350 -2800);
DISPLAY 0.872340 (-1350 -2800);
PAINT GREEN (-1350 -2800);
DISPLAY INVISIBLE (-1350 -2800);
FORCEPROP 2 LAST CDS_LIB logical_power
J 0
(-1375 -2725);
PAINT MONO (-1375 -2725);
DISPLAY INVISIBLE (-1375 -2725);
FORCEPROP 1 LAST PATH I6
J 0
(-1300 -2725);
DISPLAY 0.872340 (-1300 -2725);
PAINT AQUA (-1300 -2725);
DISPLAY INVISIBLE (-1300 -2725);
FORCEADD Q_CAP..1
R 2
(-1375 -2475);
FORCEPROP 1 LAST PART_NUMBER CH5104KEB02
J 2
(-1425 -2625);
DISPLAY 0.510638 (-1425 -2625);
DISPLAY INVISIBLE (-1425 -2625);
FORCEPROP 1 LAST VALUE 1UF
J 2
(-1425 -2425);
DISPLAY 0.510638 (-1425 -2425);
FORCEPROP 1 LAST PACK_TYPE C0402
J 2
(-1425 -2675);
DISPLAY 0.510638 (-1425 -2675);
FORCEPROP 1 LAST TOLERANCE 10%
J 2
(-1425 -2525);
DISPLAY 0.510638 (-1425 -2525);
FORCEPROP 1 LAST MATERIAL EMPTY
J 2
(-1425 -2575);
DISPLAY 0.510638 (-1425 -2575);
PAINT RED (-1425 -2575);
FORCEPROP 1 LAST VOLTAGE 25V
J 2
(-1425 -2475);
DISPLAY 0.510638 (-1425 -2475);
FORCEPROP 1 LAST $LOCATION C1318
J 2
(-1425 -2375);
DISPLAY 0.638298 (-1425 -2375);
FORCEPROP 1 LASTPIN (-1375 -2375) $PN 1
J 2
(-1385 -2395);
DISPLAY 0.787234 (-1385 -2395);
FORCEPROP 1 LASTPIN (-1375 -2575) $PN 2
J 2
(-1385 -2595);
DISPLAY 0.787234 (-1385 -2595);
FORCEPROP 2 LAST CDS_LIB pure_quanta
J 0
(-1375 -2475);
PAINT MONO (-1375 -2475);
DISPLAY INVISIBLE (-1375 -2475);
FORCEPROP 1 LAST PATH I7
J 2
(-1425 -2325);
DISPLAY 0.978723 (-1425 -2325);
PAINT WHITE (-1425 -2325);
DISPLAY INVISIBLE (-1425 -2325);
FORCEPROP 2 LAST CDS_LOCATION C1318
J 0
(-1425 -2275);
DISPLAY 1.021277 (-1425 -2275);
DISPLAY INVISIBLE (-1425 -2275);
FORCEPROP 2 LAST $SEC 1
J 0
(-1425 -2275);
DISPLAY 0.680851 (-1425 -2275);
PAINT MONO (-1425 -2275);
DISPLAY INVISIBLE (-1425 -2275);
FORCEPROP 2 LAST CDS_SEC 1
J 0
(-1425 -2275);
DISPLAY 1.021277 (-1425 -2275);
DISPLAY INVISIBLE (-1425 -2275);
FORCEADD UNIVERSAL_GND..1
(-1375 -2225);
FORCEPROP 3 LASTPIN (-1375 -2175) SIG_NAME GND\g
J 0
(-1365 -2165);
DISPLAY 0.659574 (-1365 -2165);
PAINT MONO (-1365 -2165);
DISPLAY INVISIBLE (-1365 -2165);
FORCEPROP 1 LAST HDL_POWER GND
J 1
(-1350 -2300);
DISPLAY 0.872340 (-1350 -2300);
PAINT GREEN (-1350 -2300);
DISPLAY INVISIBLE (-1350 -2300);
FORCEPROP 2 LAST CDS_LIB logical_power
J 0
(-1375 -2225);
PAINT MONO (-1375 -2225);
DISPLAY INVISIBLE (-1375 -2225);
FORCEPROP 1 LAST PATH I8
J 0
(-1300 -2225);
DISPLAY 0.872340 (-1300 -2225);
PAINT AQUA (-1300 -2225);
DISPLAY INVISIBLE (-1300 -2225);
FORCEADD Q_CAP..1
R 2
(-1375 -2000);
FORCEPROP 1 LAST PART_NUMBER CH4104K1B00
J 2
(-1425 -2150);
DISPLAY 0.510638 (-1425 -2150);
DISPLAY INVISIBLE (-1425 -2150);
FORCEPROP 1 LAST PACK_TYPE 0402
J 2
(-1425 -2200);
DISPLAY 0.510638 (-1425 -2200);
FORCEPROP 1 LAST VALUE 0.1UF
J 2
(-1425 -1950);
DISPLAY 0.510638 (-1425 -1950);
FORCEPROP 1 LAST VOLTAGE 25V
J 2
(-1425 -2000);
DISPLAY 0.510638 (-1425 -2000);
FORCEPROP 1 LAST MATERIAL X7R
J 2
(-1425 -2100);
DISPLAY 0.510638 (-1425 -2100);
FORCEPROP 1 LAST TOLERANCE 10%
J 2
(-1425 -2050);
DISPLAY 0.510638 (-1425 -2050);
FORCEPROP 1 LAST $LOCATION C1317
J 2
(-1425 -1900);
DISPLAY 0.638298 (-1425 -1900);
FORCEPROP 1 LASTPIN (-1375 -1900) $PN 1
J 2
(-1385 -1920);
DISPLAY 0.787234 (-1385 -1920);
FORCEPROP 1 LASTPIN (-1375 -2100) $PN 2
J 2
(-1385 -2120);
DISPLAY 0.787234 (-1385 -2120);
FORCEPROP 2 LAST CDS_LIB pure_quanta
J 2
(-1375 -2000);
PAINT MONO (-1375 -2000);
DISPLAY INVISIBLE (-1375 -2000);
FORCEPROP 1 LAST PATH I9
J 2
(-1425 -1850);
DISPLAY 0.978723 (-1425 -1850);
PAINT WHITE (-1425 -1850);
DISPLAY INVISIBLE (-1425 -1850);
FORCEPROP 2 LAST CDS_LOCATION C1317
J 0
(-1425 -1800);
DISPLAY 1.021277 (-1425 -1800);
DISPLAY INVISIBLE (-1425 -1800);
FORCEPROP 2 LAST $SEC 1
J 0
(-1425 -1800);
DISPLAY 0.680851 (-1425 -1800);
PAINT MONO (-1425 -1800);
DISPLAY INVISIBLE (-1425 -1800);
FORCEPROP 2 LAST CDS_SEC 1
J 0
(-1425 -1800);
DISPLAY 1.021277 (-1425 -1800);
DISPLAY INVISIBLE (-1425 -1800);
FORCEADD QUANTA_TITLE_BLOCK_C..1
(4650 -3375);
FORCEPROP 0 LAST CDS_CON_LAST_MODIFIED Fri Aug 25 14:04:14 2023
J 0
(2765 -3360);
DISPLAY INVISIBLE (2765 -3360);
FORCEPROP 2 LAST CUSTOM_TXT_CDS <XR_PAGE_TITLE>
J 0
(-3240 1875);
DISPLAY 0.638298 (-3240 1875);
PAINT PINK (-3240 1875);
DISPLAY INVISIBLE (-3240 1875);
FORCEPROP 2 LAST CUSTOM_TXT_CDS <Q_REV>
J 0
(4466 -3272);
DISPLAY 1.212766 (4466 -3272);
FORCEPROP 2 LAST CUSTOM_TXT_CDS <CON_LAST_MODIFIED>
J 0
(2765 -3360);
DISPLAY 0.978723 (2765 -3360);
FORCEPROP 2 LAST CUSTOM_TXT_CDS <NAME_2>
J 0
(1475 -3325);
FORCEPROP 2 LAST CUSTOM_TXT_CDS <NAME_1>
J 0
(1475 -3200);
FORCEPROP 2 LAST CUSTOM_TXT_CDS <Q_NUMBER>
J 0
(3247 -3272);
DISPLAY 1.212766 (3247 -3272);
FORCEPROP 2 LAST CUSTOM_TXT_CDS <Q_PROJ>
J 0
(2268 -3273);
DISPLAY 1.212766 (2268 -3273);
FORCEPROP 2 LAST CUSTOM_TXT_CDS <CON_PAGE_NUM> OF <CON_TOTAL_PAGES>
J 0
(4204 -3357);
DISPLAY 0.978723 (4204 -3357);
FORCEPROP 1 LAST Q_TITLE PWRGD_DSW_PWROK
J 0
(-4691 -3324);
DISPLAY 2.446809 (-4691 -3324);
PAINT GREEN (-4691 -3324);
FORCEPROP 1 LAST Q_DEPT 
J 1
(887 -3326);
DISPLAY 1.957447 (887 -3326);
PAINT GREEN (887 -3326);
FORCEPROP 2 LAST PAGE_BORDER TRUE
J 0
(-3240 1875);
DISPLAY 0.638298 (-3240 1875);
PAINT PINK (-3240 1875);
DISPLAY INVISIBLE (-3240 1875);
FORCEPROP 1 LAST COMMENT_BODY TRUE
J 0
(4662 -3388);
DISPLAY 0.978723 (4662 -3388);
PAINT GREEN (4662 -3388);
DISPLAY INVISIBLE (4662 -3388);
FORCEPROP 1 LAST CDS_LMAN_SYM_OUTLINE -9475,6775,100,-125
J 0
(4650 -3375);
DISPLAY 0.468085 (4650 -3375);
PAINT GREEN (4650 -3375);
DISPLAY INVISIBLE (4650 -3375);
FORCEPROP 2 LAST CDS_LIB pure_quanta
J 0
(4650 -3375);
DISPLAY INVISIBLE (4650 -3375);
FORCEPROP 2 LAST CDS_XR_PAGE_TITLE CR-244 : @S9S_MB_2U_LIB.S9S_MB_2U(SCH_1):PAGE244
J 0
(-3240 1875);
DISPLAY 0.638298 (-3240 1875);
PAINT PINK (-3240 1875);
DISPLAY INVISIBLE (-3240 1875);
FORCEADD DNS..2
(-2175 -2100);
PAINT RED (-2175 -2100);
FORCEPROP 1 LAST COMMENT_BODY TRUE
R 1
J 0
(-2100 -2325);
DISPLAY 0.872340 (-2100 -2325);
PAINT GREEN (-2100 -2325);
DISPLAY INVISIBLE (-2100 -2325);
FORCEPROP 2 LAST CDS_LIB mstr_misc
J 0
(-2175 -2100);
DISPLAY INVISIBLE (-2175 -2100);
FORCEADD DNS..2
(-1375 -2500);
PAINT RED (-1375 -2500);
FORCEPROP 1 LAST COMMENT_BODY TRUE
R 1
J 0
(-1300 -2725);
DISPLAY 0.872340 (-1300 -2725);
PAINT GREEN (-1300 -2725);
DISPLAY INVISIBLE (-1300 -2725);
FORCEPROP 2 LAST CDS_LIB mstr_misc
J 0
(-1375 -2500);
DISPLAY INVISIBLE (-1375 -2500);
FORCEADD DNS..2
(-850 -1500);
PAINT RED (-850 -1500);
FORCEPROP 2 LAST CDS_LIB mstr_misc
J 0
(-850 -1500);
DISPLAY INVISIBLE (-850 -1500);
FORCEPROP 1 LAST COMMENT_BODY TRUE
R 1
J 0
(-775 -1725);
DISPLAY 0.872340 (-775 -1725);
PAINT GREEN (-775 -1725);
DISPLAY INVISIBLE (-775 -1725);
FORCEADD DNS..2
(-1575 425);
PAINT RED (-1575 425);
FORCEPROP 1 LAST COMMENT_BODY TRUE
R 1
J 0
(-1500 200);
DISPLAY 0.872340 (-1500 200);
PAINT GREEN (-1500 200);
DISPLAY INVISIBLE (-1500 200);
FORCEPROP 2 LAST CDS_LIB mstr_misc
J 0
(-1575 425);
PAINT MONO (-1575 425);
DISPLAY INVISIBLE (-1575 425);
FORCEADD DNS..7
(25 1175);
PAINT RED (25 1175);
FORCEPROP 1 LAST COMMENT_BODY TRUE
R 1
J 0
(100 950);
DISPLAY 0.872340 (100 950);
PAINT GREEN (100 950);
DISPLAY INVISIBLE (100 950);
FORCEPROP 2 LAST CDS_LIB mstr_misc
J 0
(25 1175);
DISPLAY INVISIBLE (25 1175);
FORCEADD BOM_NOTE..1
(75 2625);
FORCEPROP 0 LAST S2 CHANGE U117 TO AL003895003(PUSH-PULL)
J 0
(-75 2475);
DISPLAY 1.021277 (-75 2475);
PAINT RED (-75 2475);
FORCEPROP 1 LAST COMMENT_BODY TRUE
J 0
(100 2725);
DISPLAY 0.978723 (100 2725);
DISPLAY INVISIBLE (100 2725);
FORCEPROP 2 LAST CDS_LIB logical_power
J 0
(75 2625);
DISPLAY INVISIBLE (75 2625);
FORCEADD DNS..2
(675 -2625);
PAINT RED (675 -2625);
FORCEPROP 2 LAST CDS_LIB mstr_misc
J 0
(675 -2625);
DISPLAY INVISIBLE (675 -2625);
FORCEPROP 1 LAST COMMENT_BODY TRUE
R 1
J 0
(750 -2850);
DISPLAY 0.872340 (750 -2850);
PAINT GREEN (750 -2850);
DISPLAY INVISIBLE (750 -2850);
FORCEADD DNS..2
(1600 -2550);
PAINT RED (1600 -2550);
FORCEPROP 1 LAST COMMENT_BODY TRUE
R 1
J 0
(1675 -2775);
DISPLAY 0.872340 (1675 -2775);
PAINT GREEN (1675 -2775);
DISPLAY INVISIBLE (1675 -2775);
FORCEPROP 2 LAST CDS_LIB mstr_misc
J 0
(1600 -2550);
PAINT MONO (1600 -2550);
DISPLAY INVISIBLE (1600 -2550);
FORCEADD CAD_NOTE..1
(1725 1625);
FORCEPROP 0 LAST S1 U94 & U117 CO-LAYOUT, U117 IS 2ND SOLUTION
J 0
(1575 1475);
DISPLAY 1.021277 (1575 1475);
PAINT SKYBLUE (1575 1475);
FORCEPROP 1 LAST COMMENT_BODY TRUE
J 0
(1750 1725);
DISPLAY 0.978723 (1750 1725);
DISPLAY INVISIBLE (1750 1725);
FORCEPROP 2 LAST CDS_LIB logical_power
J 0
(1725 1625);
DISPLAY INVISIBLE (1725 1625);
WIRE 16 -1 (-2175 -1875)(-2175 -1975);
WIRE 16 -1 (-1175 -1800)(-1175 -1850);
WIRE 16 -1 (-2250 2350)(-2250 2175);
WIRE 16 -1 (-1850 2350)(-1850 2175);
WIRE 16 -1 (-475 2400)(-475 2275);
WIRE 16 -1 (975 -1775)(975 -1875);
WIRE 16 -1 (875 -50)(875 50);
WIRE 16 -1 (-2175 -2725)(-2175 -2650);
WIRE 16 -1 (-1375 -2575)(-1375 -2675);
WIRE 16 -1 (-1375 -2100)(-1375 -2175);
WIRE 16 -1 (-1175 -2675)(-1175 -2400);
WIRE 16 -1 (-175 -425)(-175 -575);
WIRE 16 -1 (-2250 1550)(-2250 1475);
WIRE 16 -1 (-850 2000)(-850 1950);
WIRE 16 -1 (675 -2775)(675 -2700);
WIRE 16 -1 (1325 -2625)(1325 -2775);
WIRE 16 -1 (875 -850)(875 -1000);
WIRE 16 -1 (550 925)(550 1050);
WIRE 16 -1 (1425 725)(1425 800);
WIRE 16 -1 (600 1775)(375 1775);
WIRE 16 -1 (475 1150)(600 1150);
WIRE 16 -1 (600 1150)(600 1775);
WIRE 16 -1 (600 1150)(1425 1150);
FORCEPROP 0 LAST CDS_PHYS_NET_NAME FM_COMP_P3V3_STBY_CEXT
J 0
(1315 1198);
PAINT MONO (1315 1198);
DISPLAY INVISIBLE (1315 1198);
FORCEPROP 2 LAST SIG_NAME FM_COMP_P3V3_STBY_CEXT
J 0
(765 1160);
DISPLAY 0.510638 (765 1160);
PAINT WHITE (765 1160);
WIRE 16 -1 (1425 1000)(1425 1150);
WIRE 16 -1 (650 1250)(475 1250);
WIRE 16 -1 (375 1875)(650 1875);
WIRE 16 -1 (650 1875)(650 1250);
WIRE 16 -1 (650 1875)(1425 1875);
FORCEPROP 0 LAST CDS_PHYS_NET_NAME PWRGD_DSW_PWROK_R1
J 0
(915 1923);
PAINT MONO (915 1923);
DISPLAY INVISIBLE (915 1923);
FORCEPROP 2 LAST SIG_NAME PWRGD_DSW_PWROK_R1
J 0
(765 1885);
DISPLAY 0.510638 (765 1885);
PAINT WHITE (765 1885);
WIRE 16 -1 (475 1050)(550 1050);
WIRE 16 -1 (550 1725)(375 1725);
WIRE 16 -1 (550 1725)(550 1050);
WIRE 16 -1 (1075 -650)(1800 -650);
FORCEPROP 0 LAST CDS_PHYS_NET_NAME PWRGD_P3V3_AUX
J 0
(1515 -608);
PAINT MONO (1515 -608);
DISPLAY INVISIBLE (1515 -608);
FORCEPROP 2 LAST SIG_NAME PWRGD_P3V3_AUX
J 0
(1290 -640);
DISPLAY 0.446809 (1290 -640);
PAINT WHITE (1290 -640);
WIRE 16 -1 (875 -450)(875 -325);
WIRE 16 -1 (875 -250)(875 -325);
WIRE 16 -1 (875 -325)(200 -325);
FORCEPROP 0 LAST CDS_PHYS_NET_NAME PWRGD_P3V3_AUX_R2
J 0
(590 -283);
PAINT MONO (590 -283);
DISPLAY INVISIBLE (590 -283);
FORCEPROP 2 LAST SIG_NAME PWRGD_P3V3_AUX_R2
J 0
(265 -315);
DISPLAY 0.446809 (265 -315);
PAINT WHITE (265 -315);
WIRE 16 -1 (200 -325)(200 -225);
WIRE 16 -1 (200 -225)(25 -225);
WIRE 16 -1 (1600 -2425)(1600 -2300);
WIRE 16 -1 (1600 -2300)(2250 -2300);
FORCEPROP 0 LAST CDS_PHYS_NET_NAME PWRGD_DSW_PWROK
J 0
(1915 -2252);
PAINT MONO (1915 -2252);
DISPLAY INVISIBLE (1915 -2252);
FORCEPROP 2 LAST SIG_NAME PWRGD_DSW_PWROK
J 0
(1740 -2290);
DISPLAY 0.510638 (1740 -2290);
PAINT WHITE (1740 -2290);
WIRE 16 -1 (1325 -2425)(1325 -2300);
WIRE 16 -1 (1600 -2300)(1325 -2300);
WIRE 16 -1 (975 -2075)(975 -2300);
WIRE 16 -1 (1325 -2300)(975 -2300);
WIRE 16 -1 (675 -2500)(675 -2300);
WIRE 16 -1 (675 -2300)(975 -2300);
WIRE 16 -1 (500 -2300)(675 -2300);
WIRE 16 -1 (2225 -2775)(1600 -2775);
FORCEPROP 0 LAST CDS_PHYS_NET_NAME RST_RSMRST_PCH_N
J 0
(1915 -2727);
PAINT MONO (1915 -2727);
DISPLAY INVISIBLE (1915 -2727);
FORCEPROP 2 LAST SIG_NAME RST_RSMRST_PCH_N
J 0
(1740 -2765);
DISPLAY 0.510638 (1740 -2765);
PAINT WHITE (1740 -2765);
WIRE 16 -1 (1600 -2625)(1600 -2775);
WIRE 16 2175 (550 -2875)(1000 -2875);
WIRE 16 2175 (1000 -2375)(1000 -2875);
WIRE 16 2175 (550 -2375)(550 -2875);
WIRE 16 2175 (550 -2375)(1000 -2375);
WIRE 16 -1 (-475 1250)(-375 1250);
WIRE 16 -1 (-850 2200)(-850 2275);
WIRE 16 -1 (-475 1875)(-475 1250);
WIRE 16 -1 (-475 1875)(-275 1875);
WIRE 16 -1 (-475 2275)(-475 1875);
WIRE 16 -1 (-850 2275)(-475 2275);
WIRE 16 -1 (-675 425)(-1500 425);
FORCEPROP 0 LAST CDS_PHYS_NET_NAME FM_PFR_DSW_PWROK_N
J 0
(-785 473);
PAINT MONO (-785 473);
DISPLAY INVISIBLE (-785 473);
FORCEPROP 0 LAST SIG_NAME FM_PFR_DSW_PWROK_N
J 0
(-1210 435);
DISPLAY 0.510638 (-1210 435);
PAINT WHITE (-1210 435);
WIRE 16 -1 (-1850 1975)(-1850 1725);
WIRE 16 -1 (-275 1725)(-1850 1725);
FORCEPROP 0 LAST CDS_PHYS_NET_NAME FM_COMP_P3V3_AUX_ENIN
J 0
(-760 1773);
PAINT MONO (-760 1773);
DISPLAY INVISIBLE (-760 1773);
FORCEPROP 2 LAST SIG_NAME FM_COMP_P3V3_AUX_ENIN
J 0
(-1525 1735);
DISPLAY 0.510638 (-1525 1735);
PAINT WHITE (-1525 1735);
WIRE 16 -1 (-1850 425)(-1700 425);
WIRE 16 -1 (-1850 1050)(-1850 425);
WIRE 16 -1 (-1850 1725)(-1850 1050);
WIRE 16 -1 (-1850 1050)(-375 1050);
FORCEPROP 0 LAST CDS_PHYS_NET_NAME FM_COMP_P3V3_AUX_ENIN
J 0
(-860 1098);
PAINT MONO (-860 1098);
DISPLAY INVISIBLE (-860 1098);
WIRE 16 -1 (-2250 1825)(-2250 1750);
WIRE 16 -1 (-2250 1975)(-2250 1825);
WIRE 16 -1 (-2250 1825)(-2125 1825);
WIRE 16 -1 (-275 1825)(-2125 1825);
FORCEPROP 0 LAST CDS_PHYS_NET_NAME FM_COMP_P3V3_AUX_VIN
J 0
(-860 1873);
PAINT MONO (-860 1873);
DISPLAY INVISIBLE (-860 1873);
FORCEPROP 2 LAST SIG_NAME FM_COMP_P3V3_AUX_VIN
J 0
(-1525 1835);
DISPLAY 0.510638 (-1525 1835);
PAINT WHITE (-1525 1835);
WIRE 16 -1 (-2125 1825)(-2125 1150);
WIRE 16 -1 (-2125 1150)(-375 1150);
FORCEPROP 0 LAST CDS_PHYS_NET_NAME FM_COMP_P3V3_AUX_VIN
J 0
(-960 1198);
PAINT MONO (-960 1198);
DISPLAY INVISIBLE (-960 1198);
WIRE 16 -1 (-2125 175)(-2125 1150);
WIRE 16 -1 (-2125 175)(-1700 175);
WIRE 16 -1 (-1500 175)(-175 175);
FORCEPROP 0 LAST CDS_PHYS_NET_NAME FM_COMP_P3V3_AUX_VIN_R
J 0
(-785 223);
PAINT MONO (-785 223);
DISPLAY INVISIBLE (-785 223);
FORCEPROP 0 LAST SIG_NAME FM_COMP_P3V3_AUX_VIN_R
J 0
(-1210 185);
DISPLAY 0.510638 (-1210 185);
PAINT WHITE (-1210 185);
WIRE 16 -1 (-175 -25)(-175 175);
WIRE 16 2175 (-1125 -1600)(-550 -1600);
WIRE 16 2175 (-550 -1375)(-550 -1600);
WIRE 16 2175 (-1125 -1375)(-1125 -1600);
WIRE 16 2175 (-1125 -1375)(-550 -1375);
WIRE 16 -1 (-1375 -1850)(-1375 -1900);
WIRE 16 -1 (-1375 -1850)(-1175 -1850);
WIRE 16 -1 (-1175 -2200)(-1175 -1850);
WIRE 16 -1 (-1100 -2200)(-1175 -2200);
WIRE 16 -1 (-975 -1500)(-1775 -1500);
WIRE 16 -1 (-1375 -2375)(-1375 -2300);
WIRE 16 -1 (-1100 -2300)(-1375 -2300);
WIRE 16 -1 (-1375 -2300)(-1775 -2300);
WIRE 16 -1 (-1775 -1500)(-1775 -2300);
WIRE 16 -1 (-2175 -2175)(-2175 -2300);
WIRE 16 -1 (-1775 -2300)(-2175 -2300);
WIRE 16 -1 (-2175 -2450)(-2175 -2375);
WIRE 16 -1 (-2175 -2375)(-2175 -2300);
WIRE 16 -1 (-3000 -2375)(-2175 -2375);
FORCEPROP 0 LAST CDS_PHYS_NET_NAME PWRGD_DSW_PWROK_R1
J 0
(-2685 -2327);
PAINT MONO (-2685 -2327);
DISPLAY INVISIBLE (-2685 -2327);
FORCEPROP 2 LAST SIG_NAME PWRGD_DSW_PWROK_R1
J 0
(-2885 -2365);
DISPLAY 0.510638 (-2885 -2365);
PAINT WHITE (-2885 -2365);
WIRE 16 -1 (-775 -1500)(75 -1500);
WIRE 16 -1 (300 -2300)(75 -2300);
WIRE 16 -1 (75 -1500)(75 -2300);
WIRE 16 -1 (-500 -2300)(75 -2300);
FORCEPROP 0 LAST CDS_PHYS_NET_NAME PWRGD_DSW_PWROK_R2
J 0
(-35 -2252);
PAINT MONO (-35 -2252);
DISPLAY INVISIBLE (-35 -2252);
FORCEPROP 2 LAST SIG_NAME PWRGD_DSW_PWROK_R2
J 0
(-410 -2290);
DISPLAY 0.510638 (-410 -2290);
PAINT WHITE (-410 -2290);
WIRE 16 -1 (-1175 -2400)(-1100 -2400);
DOT 1 (-2175 -2375);
DOT 1 (-2175 -2300);
DOT 1 (-1775 -2300);
DOT 1 (-1375 -2300);
DOT 1 (75 -2300);
DOT 1 (-1175 -1850);
DOT 1 (-2125 1150);
DOT 1 (-2250 1825);
DOT 1 (-2125 1825);
DOT 1 (-1850 1050);
DOT 1 (-1850 1725);
DOT 1 (-475 1875);
DOT 1 (-475 2275);
DOT 1 (675 -2300);
DOT 1 (975 -2300);
DOT 1 (1325 -2300);
DOT 1 (1600 -2300);
DOT 1 (875 -325);
DOT 1 (550 1050);
DOT 1 (600 1150);
DOT 1 (650 1875);
FORCENOTE
20221201 ADD R4807
(-1300 -1350) 0;
DISPLAY LEFT (-1300 -1350);
DISPLAY 1.063830 (-1300 -1350);
PAINT WHITE (-1300 -1350);
FORCENOTE
20221201 ADD R4808
(375 -2950) 0;
DISPLAY LEFT (375 -2950);
DISPLAY 1.063830 (375 -2950);
PAINT WHITE (375 -2950);
QUIT
